FILE_TYPE = MACRO_DRAWING;
SET COLOR_WIRE YELLOW;
SET COLOR_PROP MONO;
SET COLOR_DOT WHITE;
SET COLOR_ARC YELLOW;
SET COLOR_BODY GREEN;
SET COLOR_NOTE MONO;
SET PROP_DISPLAY VALUE;
SET PAGE_NUMBER P206;
FORCEADD PVCCIO_CPU1..1
(-1375 4150);
FORCEPROP 3 LASTPIN (-1375 4100) SIG_NAME PVCCIO_CPU1\g
J 0
(-1365 4110);
DISPLAY 0.659574 (-1365 4110);
PAINT MONO (-1365 4110);
DISPLAY INVISIBLE (-1365 4110);
FORCEPROP 1 LAST HDL_POWER PVCCIO_CPU1
J 1
(-1375 4200);
DISPLAY 0.872340 (-1375 4200);
PAINT GREEN (-1375 4200);
DISPLAY INVISIBLE (-1375 4200);
FORCEPROP 1 LAST BODY_TYPE PLUMBING
J 0
(-1420 4107);
DISPLAY 0.340426 (-1420 4107);
PAINT GREEN (-1420 4107);
DISPLAY INVISIBLE (-1420 4107);
FORCEPROP 1 LAST VOLTAGE 1.1V
J 0
(-1420 4107);
DISPLAY 0.340426 (-1420 4107);
PAINT SKYBLUE (-1420 4107);
DISPLAY INVISIBLE (-1420 4107);
FORCEPROP 2 LAST CDS_LIB mstr_symbols
J 0
(-1375 4150);
PAINT ORANGE (-1375 4150);
DISPLAY INVISIBLE (-1375 4150);
FORCEPROP 1 LAST PATH I1
J 0
(-1325 4175);
DISPLAY 0.872340 (-1325 4175);
PAINT AQUA (-1325 4175);
DISPLAY INVISIBLE (-1325 4175);
FORCEADD OFFPAGE..2
(-1150 2825);
FORCEPROP 2 LAST $XR0 206 
J 0
(-961 2825);
DISPLAY 0.638298 (-961 2825);
PAINT MONO (-961 2825);
FORCEPROP 1 LAST COMMENT_BODY TRUE
J 0
(-1195 2730);
DISPLAY 1.170213 (-1195 2730);
PAINT PEACH (-1195 2730);
DISPLAY INVISIBLE (-1195 2730);
FORCEPROP 1 LAST OFFPAGE TRUE
J 0
(-825 2700);
DISPLAY 1.170213 (-825 2700);
PAINT GREEN (-825 2700);
DISPLAY INVISIBLE (-825 2700);
FORCEPROP 2 LAST PATH I10
J 0
(-950 2875);
DISPLAY 1.021277 (-950 2875);
PAINT ORANGE (-950 2875);
DISPLAY INVISIBLE (-950 2875);
FORCEPROP 2 LAST CDS_LIB mstr_standard
J 0
(-1150 2825);
PAINT ORANGE (-1150 2825);
DISPLAY INVISIBLE (-1150 2825);
FORCEPROP 2 LAST ROOM PVCCIN_CPU1_VR
J 0
(-1575 2900);
DISPLAY 1.361702 (-1575 2900);
PAINT WHITE (-1575 2900);
DISPLAY INVISIBLE (-1575 2900);
FORCEADD OFFPAGE..1
(-7500 1525);
FORCEPROP 2 LAST $XR0 210 
J 0
(-7752 1525);
DISPLAY 0.638298 (-7752 1525);
PAINT MONO (-7752 1525);
FORCEPROP 1 LAST COMMENT_BODY TRUE
J 0
(-7375 1425);
DISPLAY 1.170213 (-7375 1425);
PAINT PEACH (-7375 1425);
DISPLAY INVISIBLE (-7375 1425);
FORCEPROP 1 LAST OFFPAGE TRUE
J 0
(-7175 1400);
DISPLAY 1.170213 (-7175 1400);
PAINT GREEN (-7175 1400);
DISPLAY INVISIBLE (-7175 1400);
FORCEPROP 2 LAST PATH I101
J 0
(-7450 1600);
DISPLAY 1.021277 (-7450 1600);
PAINT ORANGE (-7450 1600);
DISPLAY INVISIBLE (-7450 1600);
FORCEPROP 2 LAST CDS_LIB mstr_standard
J 0
(-7500 1525);
PAINT ORANGE (-7500 1525);
DISPLAY INVISIBLE (-7500 1525);
FORCEPROP 2 LAST ROOM PVCCIN_CPU1_VR
J 0
(-8050 1600);
DISPLAY 1.361702 (-8050 1600);
PAINT WHITE (-8050 1600);
DISPLAY INVISIBLE (-8050 1600);
FORCEADD OFFPAGE..1
(-7500 1475);
FORCEPROP 2 LAST $XR0 210 
J 0
(-7752 1475);
DISPLAY 0.638298 (-7752 1475);
PAINT MONO (-7752 1475);
FORCEPROP 1 LAST COMMENT_BODY TRUE
J 0
(-7375 1375);
DISPLAY 1.170213 (-7375 1375);
PAINT PEACH (-7375 1375);
DISPLAY INVISIBLE (-7375 1375);
FORCEPROP 1 LAST OFFPAGE TRUE
J 0
(-7175 1350);
DISPLAY 1.170213 (-7175 1350);
PAINT GREEN (-7175 1350);
DISPLAY INVISIBLE (-7175 1350);
FORCEPROP 2 LAST PATH I102
J 0
(-7450 1550);
DISPLAY 1.021277 (-7450 1550);
PAINT ORANGE (-7450 1550);
DISPLAY INVISIBLE (-7450 1550);
FORCEPROP 2 LAST CDS_LIB mstr_standard
J 0
(-7500 1475);
PAINT ORANGE (-7500 1475);
DISPLAY INVISIBLE (-7500 1475);
FORCEPROP 2 LAST ROOM PVCCIN_CPU1_VR
J 0
(-8050 1550);
DISPLAY 1.361702 (-8050 1550);
PAINT WHITE (-8050 1550);
DISPLAY INVISIBLE (-8050 1550);
FORCEADD P3V3_STBY..1
(-4350 4600);
FORCEPROP 3 LASTPIN (-4350 4550) SIG_NAME P3V3_STBY\g
J 0
(-4340 4560);
DISPLAY 0.659574 (-4340 4560);
PAINT MONO (-4340 4560);
DISPLAY INVISIBLE (-4340 4560);
FORCEPROP 1 LAST HDL_POWER P3V3_STBY
J 0
(-4650 4475);
DISPLAY 0.872340 (-4650 4475);
PAINT GREEN (-4650 4475);
DISPLAY INVISIBLE (-4650 4475);
FORCEPROP 1 LAST BODY_TYPE PLUMBING
J 0
(-4395 4557);
DISPLAY 0.340426 (-4395 4557);
PAINT GREEN (-4395 4557);
DISPLAY INVISIBLE (-4395 4557);
FORCEPROP 1 LAST SIZE 1B
J 0
(-4305 4622);
DISPLAY 0.340426 (-4305 4622);
PAINT GREEN (-4305 4622);
DISPLAY INVISIBLE (-4305 4622);
FORCEPROP 2 LAST CDS_LIB mstr_symbols
J 0
(-4350 4600);
PAINT ORANGE (-4350 4600);
DISPLAY INVISIBLE (-4350 4600);
FORCEPROP 1 LAST PATH I103
J 0
(-4305 4602);
DISPLAY 0.340426 (-4305 4602);
PAINT GREEN (-4305 4602);
DISPLAY INVISIBLE (-4305 4602);
FORCEPROP 1 LAST VOLTAGE 3.3V
J 0
(-4395 4557);
DISPLAY 0.340426 (-4395 4557);
PAINT SKYBLUE (-4395 4557);
DISPLAY INVISIBLE (-4395 4557);
FORCEADD P3V3_STBY..1
(-3075 4575);
FORCEPROP 3 LASTPIN (-3075 4525) SIG_NAME P3V3_STBY\g
J 0
(-3065 4535);
DISPLAY 0.659574 (-3065 4535);
PAINT MONO (-3065 4535);
DISPLAY INVISIBLE (-3065 4535);
FORCEPROP 1 LAST HDL_POWER P3V3_STBY
J 0
(-3375 4450);
DISPLAY 0.872340 (-3375 4450);
PAINT GREEN (-3375 4450);
DISPLAY INVISIBLE (-3375 4450);
FORCEPROP 1 LAST BODY_TYPE PLUMBING
J 0
(-3120 4532);
DISPLAY 0.340426 (-3120 4532);
PAINT GREEN (-3120 4532);
DISPLAY INVISIBLE (-3120 4532);
FORCEPROP 1 LAST SIZE 1B
J 0
(-3030 4597);
DISPLAY 0.340426 (-3030 4597);
PAINT GREEN (-3030 4597);
DISPLAY INVISIBLE (-3030 4597);
FORCEPROP 1 LAST PATH I104
J 0
(-3030 4577);
DISPLAY 0.340426 (-3030 4577);
PAINT GREEN (-3030 4577);
DISPLAY INVISIBLE (-3030 4577);
FORCEPROP 2 LAST CDS_LIB mstr_symbols
J 0
(-3075 4575);
PAINT ORANGE (-3075 4575);
DISPLAY INVISIBLE (-3075 4575);
FORCEPROP 1 LAST VOLTAGE 3.3V
J 0
(-3120 4532);
DISPLAY 0.340426 (-3120 4532);
PAINT SKYBLUE (-3120 4532);
DISPLAY INVISIBLE (-3120 4532);
FORCEADD OFFPAGE..2
(-1150 3125);
FORCEPROP 2 LAST $XR0 95 
J 0
(-961 3125);
DISPLAY 0.638298 (-961 3125);
PAINT MONO (-961 3125);
FORCEPROP 1 LAST COMMENT_BODY TRUE
J 0
(-1195 3030);
DISPLAY 1.170213 (-1195 3030);
PAINT PEACH (-1195 3030);
DISPLAY INVISIBLE (-1195 3030);
FORCEPROP 1 LAST OFFPAGE TRUE
J 0
(-825 3000);
DISPLAY 1.170213 (-825 3000);
PAINT GREEN (-825 3000);
DISPLAY INVISIBLE (-825 3000);
FORCEPROP 2 LAST PATH I109
J 0
(-975 3200);
DISPLAY 1.021277 (-975 3200);
PAINT ORANGE (-975 3200);
DISPLAY INVISIBLE (-975 3200);
FORCEPROP 2 LAST CDS_LIB mstr_standard
J 0
(-1150 3125);
PAINT ORANGE (-1150 3125);
DISPLAY INVISIBLE (-1150 3125);
FORCEPROP 2 LAST ROOM PVCCIN_CPU1_VR
J 0
(-1575 3200);
DISPLAY 1.361702 (-1575 3200);
PAINT WHITE (-1575 3200);
DISPLAY INVISIBLE (-1575 3200);
FORCEADD OFFPAGE..3
(-1175 2775);
FORCEPROP 2 LAST $XR2 213 
J 0
(-751 2775);
DISPLAY 0.638298 (-751 2775);
PAINT MONO (-751 2775);
FORCEPROP 2 LAST $XR1 193 
J 0
(-871 2775);
DISPLAY 0.638298 (-871 2775);
PAINT MONO (-871 2775);
FORCEPROP 2 LAST $XR0 55 
J 0
(-961 2775);
DISPLAY 0.638298 (-961 2775);
PAINT MONO (-961 2775);
FORCEPROP 1 LAST COMMENT_BODY TRUE
J 0
(-1225 2675);
DISPLAY 1.170213 (-1225 2675);
PAINT PEACH (-1225 2675);
DISPLAY INVISIBLE (-1225 2675);
FORCEPROP 1 LAST OFFPAGE TRUE
J 0
(-850 2650);
DISPLAY 1.170213 (-850 2650);
PAINT GREEN (-850 2650);
DISPLAY INVISIBLE (-850 2650);
FORCEPROP 2 LAST PATH I11
J 0
(-975 2850);
DISPLAY 1.021277 (-975 2850);
PAINT ORANGE (-975 2850);
DISPLAY INVISIBLE (-975 2850);
FORCEPROP 2 LAST CDS_LIB mstr_standard
J 0
(-1175 2775);
PAINT ORANGE (-1175 2775);
DISPLAY INVISIBLE (-1175 2775);
FORCEPROP 2 LAST ROOM PVCCIN_CPU1_VR
J 0
(-1575 2850);
DISPLAY 1.361702 (-1575 2850);
PAINT WHITE (-1575 2850);
DISPLAY INVISIBLE (-1575 2850);
FORCEADD RES..2
(-4500 925);
FORCEPROP 1 LAST VALUE 3.16K
J 0
(-4455 1000);
DISPLAY 0.617021 (-4455 1000);
PAINT SKYBLUE (-4455 1000);
FORCEPROP 1 LAST LOCATION R9N7
J 0
(-4455 1050);
DISPLAY 0.617021 (-4455 1050);
PAINT AQUA (-4455 1050);
FORCEPROP 1 LAST PART_NUMBER G21796-043
J 0
(-4460 800);
DISPLAY 0.617021 (-4460 800);
PAINT BLUE (-4460 800);
FORCEPROP 1 LAST MATERIAL CHIP
J 0
(-4460 850);
DISPLAY 0.617021 (-4460 850);
PAINT SKYBLUE (-4460 850);
FORCEPROP 1 LAST WATTAGE 1/16W
J 0
(-4460 900);
DISPLAY 0.617021 (-4460 900);
PAINT SKYBLUE (-4460 900);
FORCEPROP 1 LASTPIN (-4500 825) $PN 2
J 0
(-4495 835);
DISPLAY 0.617021 (-4495 835);
PAINT WHITE (-4495 835);
FORCEPROP 1 LASTPIN (-4500 1025) $PN 1
J 0
(-4495 987);
DISPLAY 0.617021 (-4495 987);
PAINT WHITE (-4495 987);
FORCEPROP 1 LAST PACK_TYPE 0402
J 0
(-4460 750);
DISPLAY 0.617021 (-4460 750);
PAINT SKYBLUE (-4460 750);
FORCEPROP 1 LAST TOLERANCE 1%
J 0
(-4455 950);
DISPLAY 0.617021 (-4455 950);
PAINT SKYBLUE (-4455 950);
FORCEPROP 2 LAST SEC_TYPE 0402
J 0
(-4450 1150);
DISPLAY 1.021277 (-4450 1150);
PAINT ORANGE (-4450 1150);
DISPLAY INVISIBLE (-4450 1150);
FORCEPROP 0 LAST SEC 1
J 0
(-4450 1200);
DISPLAY 0.680851 (-4450 1200);
PAINT MONO (-4450 1200);
DISPLAY INVISIBLE (-4450 1200);
FORCEPROP 2 LAST CDS_LOCATION R9N7
J 0
(-4455 1050);
DISPLAY 0.617021 (-4455 1050);
PAINT AQUA (-4455 1050);
DISPLAY INVISIBLE (-4455 1050);
FORCEPROP 1 LAST PATH I111
J 0
(-4450 1100);
DISPLAY 0.978723 (-4450 1100);
PAINT WHITE (-4450 1100);
DISPLAY INVISIBLE (-4450 1100);
FORCEPROP 0 LAST ROOM PVCCIN_CPU1_VR
J 0
(-4450 1150);
DISPLAY 1.021277 (-4450 1150);
PAINT ORANGE (-4450 1150);
DISPLAY INVISIBLE (-4450 1150);
FORCEPROP 2 LAST CDS_LIB mstr_discrete
J 0
(-4500 925);
PAINT ORANGE (-4500 925);
DISPLAY INVISIBLE (-4500 925);
FORCEADD RES..2
(-4825 925);
FORCEPROP 1 LAST TOLERANCE 1%
J 0
(-4780 950);
DISPLAY 0.617021 (-4780 950);
PAINT SKYBLUE (-4780 950);
FORCEPROP 1 LAST VALUE 4.02K
J 0
(-4780 1000);
DISPLAY 0.617021 (-4780 1000);
PAINT SKYBLUE (-4780 1000);
FORCEPROP 1 LAST PART_NUMBER G21796-082
J 0
(-4785 800);
DISPLAY 0.617021 (-4785 800);
PAINT BLUE (-4785 800);
FORCEPROP 1 LAST MATERIAL CHIP
J 0
(-4785 850);
DISPLAY 0.617021 (-4785 850);
PAINT SKYBLUE (-4785 850);
FORCEPROP 1 LASTPIN (-4825 1025) $PN 1
J 0
(-4820 987);
DISPLAY 0.617021 (-4820 987);
PAINT WHITE (-4820 987);
FORCEPROP 1 LASTPIN (-4825 825) $PN 2
J 0
(-4820 835);
DISPLAY 0.617021 (-4820 835);
PAINT WHITE (-4820 835);
FORCEPROP 1 LAST PACK_TYPE 0402
J 0
(-4785 750);
DISPLAY 0.617021 (-4785 750);
PAINT SKYBLUE (-4785 750);
FORCEPROP 1 LAST LOCATION R9N8
J 0
(-4780 1050);
DISPLAY 0.617021 (-4780 1050);
PAINT AQUA (-4780 1050);
FORCEPROP 1 LAST WATTAGE 1/16W
J 0
(-4785 900);
DISPLAY 0.617021 (-4785 900);
PAINT SKYBLUE (-4785 900);
FORCEPROP 2 LAST SEC_TYPE 0402
J 0
(-4775 1150);
DISPLAY 1.021277 (-4775 1150);
PAINT ORANGE (-4775 1150);
DISPLAY INVISIBLE (-4775 1150);
FORCEPROP 0 LAST SEC 1
J 0
(-4775 1200);
DISPLAY 0.680851 (-4775 1200);
PAINT MONO (-4775 1200);
DISPLAY INVISIBLE (-4775 1200);
FORCEPROP 2 LAST CDS_LOCATION R9N8
J 0
(-4780 1050);
DISPLAY 0.617021 (-4780 1050);
PAINT AQUA (-4780 1050);
DISPLAY INVISIBLE (-4780 1050);
FORCEPROP 1 LAST PATH I112
J 0
(-4775 1100);
DISPLAY 0.978723 (-4775 1100);
PAINT WHITE (-4775 1100);
DISPLAY INVISIBLE (-4775 1100);
FORCEPROP 0 LAST ROOM PVCCIN_CPU1_VR
J 0
(-4775 1150);
DISPLAY 1.021277 (-4775 1150);
PAINT ORANGE (-4775 1150);
DISPLAY INVISIBLE (-4775 1150);
FORCEPROP 2 LAST CDS_LIB mstr_discrete
J 0
(-4825 925);
PAINT ORANGE (-4825 925);
DISPLAY INVISIBLE (-4825 925);
FORCEADD RES..1
(-1200 3375);
FORCEPROP 1 LAST PART_NUMBER G21796-250
J 0
(-1250 3475);
DISPLAY 0.617021 (-1250 3475);
PAINT BLUE (-1250 3475);
FORCEPROP 1 LASTPIN (-1100 3375) $PN 2
J 0
(-1138 3387);
DISPLAY 0.617021 (-1138 3387);
PAINT ORANGE (-1138 3387);
FORCEPROP 1 LAST LOCATION R1C30
J 0
(-1250 3425);
DISPLAY 0.617021 (-1250 3425);
PAINT AQUA (-1250 3425);
FORCEPROP 1 LAST TOLERANCE 1.0%
J 0
(-1200 3275);
DISPLAY 0.617021 (-1200 3275);
PAINT SKYBLUE (-1200 3275);
FORCEPROP 1 LAST VALUE 22.1
J 2
(-1225 3275);
DISPLAY 0.617021 (-1225 3275);
PAINT SKYBLUE (-1225 3275);
FORCEPROP 1 LAST WATTAGE 1/16W
J 2
(-1225 3225);
DISPLAY 0.617021 (-1225 3225);
PAINT SKYBLUE (-1225 3225);
FORCEPROP 1 LAST MATERIAL CHIP
J 0
(-1200 3225);
DISPLAY 0.617021 (-1200 3225);
PAINT SKYBLUE (-1200 3225);
FORCEPROP 1 LAST PACK_TYPE 0402
J 0
(-950 3225);
DISPLAY 0.617021 (-950 3225);
PAINT SKYBLUE (-950 3225);
FORCEPROP 1 LASTPIN (-1300 3375) $PN 1
J 0
(-1288 3387);
DISPLAY 0.617021 (-1288 3387);
PAINT ORANGE (-1288 3387);
FORCEPROP 2 LAST SEC_TYPE 0402
J 0
(-1250 3575);
DISPLAY 1.021277 (-1250 3575);
PAINT ORANGE (-1250 3575);
DISPLAY INVISIBLE (-1250 3575);
FORCEPROP 2 LAST SEC 1
J 0
(-1250 3575);
DISPLAY 0.680851 (-1250 3575);
PAINT MONO (-1250 3575);
DISPLAY INVISIBLE (-1250 3575);
FORCEPROP 2 LAST ROOM PVCCIN_CPU1_VR
J 0
(-1250 3475);
DISPLAY 1.361702 (-1250 3475);
PAINT WHITE (-1250 3475);
DISPLAY INVISIBLE (-1250 3475);
FORCEPROP 1 LAST PATH I113
J 0
(-1250 3525);
DISPLAY 0.978723 (-1250 3525);
PAINT WHITE (-1250 3525);
DISPLAY INVISIBLE (-1250 3525);
FORCEPROP 2 LAST CDS_LOCATION R1C30
J 0
(-1250 3425);
DISPLAY 0.617021 (-1250 3425);
PAINT AQUA (-1250 3425);
DISPLAY INVISIBLE (-1250 3425);
FORCEPROP 2 LAST CDS_LIB mstr_discrete
J 0
(-1200 3375);
PAINT MONO (-1200 3375);
DISPLAY INVISIBLE (-1200 3375);
FORCEADD CAP..1
(-1450 2150);
FORCEPROP 1 LAST VOLTAGE 50V
J 0
(-1400 2150);
DISPLAY 0.617021 (-1400 2150);
PAINT SKYBLUE (-1400 2150);
FORCEPROP 1 LAST TOLERANCE 10%
J 0
(-1400 2100);
DISPLAY 0.617021 (-1400 2100);
PAINT SKYBLUE (-1400 2100);
FORCEPROP 1 LASTPIN (-1450 2050) $PN 2
J 0
(-1440 2030);
DISPLAY 0.617021 (-1440 2030);
PAINT ORANGE (-1440 2030);
FORCEPROP 1 LAST VALUE 1000PF
J 0
(-1400 2200);
DISPLAY 0.617021 (-1400 2200);
PAINT SKYBLUE (-1400 2200);
FORCEPROP 1 LASTPIN (-1450 2250) $PN 1
J 0
(-1440 2230);
DISPLAY 0.617021 (-1440 2230);
PAINT ORANGE (-1440 2230);
FORCEPROP 1 LAST PACK_TYPE 0402LF
J 0
(-1400 1950);
DISPLAY 0.617021 (-1400 1950);
PAINT SKYBLUE (-1400 1950);
FORCEPROP 1 LAST MATERIAL X7R
J 0
(-1400 2050);
DISPLAY 0.617021 (-1400 2050);
PAINT SKYBLUE (-1400 2050);
FORCEPROP 1 LAST PART_NUMBER A36096-046
J 0
(-1400 2000);
DISPLAY 0.617021 (-1400 2000);
PAINT BLUE (-1400 2000);
FORCEPROP 1 LAST LOCATION C1C23
J 0
(-1400 2250);
DISPLAY 0.617021 (-1400 2250);
PAINT AQUA (-1400 2250);
FORCEPROP 0 LAST ROOM PVCCIN_CPU1_VR
J 0
(-1400 2350);
DISPLAY 1.021277 (-1400 2350);
PAINT ORANGE (-1400 2350);
DISPLAY INVISIBLE (-1400 2350);
FORCEPROP 2 LAST SEC 1
J 0
(-1400 2350);
DISPLAY 0.680851 (-1400 2350);
PAINT MONO (-1400 2350);
DISPLAY INVISIBLE (-1400 2350);
FORCEPROP 2 LAST SEC_TYPE 0402LF
J 0
(-1400 2350);
DISPLAY 1.021277 (-1400 2350);
PAINT ORANGE (-1400 2350);
DISPLAY INVISIBLE (-1400 2350);
FORCEPROP 1 LAST PATH I114
J 0
(-1400 2300);
DISPLAY 0.978723 (-1400 2300);
PAINT WHITE (-1400 2300);
DISPLAY INVISIBLE (-1400 2300);
FORCEPROP 2 LAST CDS_LOCATION C1C23
J 0
(-1400 2250);
DISPLAY 0.617021 (-1400 2250);
PAINT AQUA (-1400 2250);
DISPLAY INVISIBLE (-1400 2250);
FORCEPROP 2 LAST CDS_LIB mstr_discrete
J 0
(-1450 2150);
PAINT MONO (-1450 2150);
DISPLAY INVISIBLE (-1450 2150);
FORCEADD GND..1
(-1450 1925);
FORCEPROP 3 LASTPIN (-1450 1975) SIG_NAME GND\g
J 0
(-1440 1985);
DISPLAY 0.659574 (-1440 1985);
PAINT MONO (-1440 1985);
DISPLAY INVISIBLE (-1440 1985);
FORCEPROP 1 LAST HDL_POWER GND
J 0
(-1450 2075);
DISPLAY 1.170213 (-1450 2075);
PAINT GREEN (-1450 2075);
DISPLAY INVISIBLE (-1450 2075);
FORCEPROP 1 LAST BODY_TYPE PLUMBING
J 0
(-1495 1882);
DISPLAY 0.340426 (-1495 1882);
PAINT GREEN (-1495 1882);
DISPLAY INVISIBLE (-1495 1882);
FORCEPROP 2 LAST ROOM PVCCIN_CPU1_VR
J 0
(-2025 2000);
DISPLAY 1.361702 (-2025 2000);
PAINT WHITE (-2025 2000);
DISPLAY INVISIBLE (-2025 2000);
FORCEPROP 1 LAST PATH I115
J 0
(-1375 1925);
DISPLAY 0.872340 (-1375 1925);
PAINT AQUA (-1375 1925);
DISPLAY INVISIBLE (-1375 1925);
FORCEPROP 2 LAST CDS_LIB mstr_symbols
J 0
(-1450 1925);
PAINT MONO (-1450 1925);
DISPLAY INVISIBLE (-1450 1925);
FORCEPROP 1 LAST SIZE 1B
J 0
(-1375 1875);
DISPLAY 1.170213 (-1375 1875);
PAINT AQUA (-1375 1875);
DISPLAY INVISIBLE (-1375 1875);
FORCEPROP 1 LAST VOLTAGE 0
J 0
(-1450 1925);
PAINT SKYBLUE (-1450 1925);
DISPLAY INVISIBLE (-1450 1925);
FORCEADD RES..1
(-2175 2725);
FORCEPROP 1 LASTPIN (-2075 2725) $PN 2
J 0
(-2113 2737);
DISPLAY 0.617021 (-2113 2737);
PAINT ORANGE (-2113 2737);
FORCEPROP 1 LAST LOCATION R1D1
J 0
(-2300 2675);
DISPLAY 0.617021 (-2300 2675);
PAINT AQUA (-2300 2675);
FORCEPROP 1 LASTPIN (-2275 2725) $PN 1
J 0
(-2263 2737);
DISPLAY 0.617021 (-2263 2737);
PAINT ORANGE (-2263 2737);
FORCEPROP 1 LAST MATERIAL CHIP
J 0
(-2175 2575);
DISPLAY 0.617021 (-2175 2575);
PAINT SKYBLUE (-2175 2575);
FORCEPROP 1 LAST PART_NUMBER G21796-074
J 0
(-2075 2675);
DISPLAY 0.617021 (-2075 2675);
PAINT BLUE (-2075 2675);
FORCEPROP 1 LAST TOLERANCE 1%
J 0
(-2175 2625);
DISPLAY 0.617021 (-2175 2625);
PAINT SKYBLUE (-2175 2625);
FORCEPROP 1 LAST WATTAGE 1/16W
J 2
(-2200 2575);
DISPLAY 0.617021 (-2200 2575);
PAINT SKYBLUE (-2200 2575);
FORCEPROP 1 LAST VALUE 33.2
J 2
(-2200 2625);
DISPLAY 0.617021 (-2200 2625);
PAINT SKYBLUE (-2200 2625);
FORCEPROP 1 LAST PACK_TYPE 0402
J 0
(-2075 2625);
DISPLAY 0.617021 (-2075 2625);
PAINT SKYBLUE (-2075 2625);
FORCEPROP 2 LAST SEC_TYPE 0402
J 0
(-2225 2925);
DISPLAY 1.021277 (-2225 2925);
PAINT ORANGE (-2225 2925);
DISPLAY INVISIBLE (-2225 2925);
FORCEPROP 2 LAST SEC 1
J 0
(-2225 2925);
DISPLAY 0.680851 (-2225 2925);
PAINT MONO (-2225 2925);
DISPLAY INVISIBLE (-2225 2925);
FORCEPROP 1 LAST PATH I116
J 0
(-2225 2875);
DISPLAY 0.978723 (-2225 2875);
PAINT WHITE (-2225 2875);
DISPLAY INVISIBLE (-2225 2875);
FORCEPROP 2 LAST CDS_LIB mstr_discrete
J 0
(-2175 2725);
PAINT MONO (-2175 2725);
DISPLAY INVISIBLE (-2175 2725);
FORCEPROP 2 LAST CDS_LOCATION R1D1
J 0
(-2225 2775);
DISPLAY 0.617021 (-2225 2775);
PAINT AQUA (-2225 2775);
DISPLAY INVISIBLE (-2225 2775);
FORCEADD RES..1
(-2375 3025);
FORCEPROP 1 LAST PART_NUMBER G21796-074
J 0
(-2425 3125);
DISPLAY 0.617021 (-2425 3125);
PAINT BLUE (-2425 3125);
FORCEPROP 1 LAST LOCATION R9P3
J 0
(-2425 3075);
DISPLAY 0.617021 (-2425 3075);
PAINT AQUA (-2425 3075);
FORCEPROP 1 LASTPIN (-2475 3025) $PN 1
J 0
(-2463 3037);
DISPLAY 0.617021 (-2463 3037);
PAINT ORANGE (-2463 3037);
FORCEPROP 1 LAST PACK_TYPE 0402
J 0
(-2275 3075);
DISPLAY 0.617021 (-2275 3075);
PAINT SKYBLUE (-2275 3075);
FORCEPROP 1 LASTPIN (-2275 3025) $PN 2
J 0
(-2313 3037);
DISPLAY 0.617021 (-2313 3037);
PAINT ORANGE (-2313 3037);
FORCEPROP 1 LAST VALUE 33.2
J 2
(-2400 2925);
DISPLAY 0.617021 (-2400 2925);
PAINT SKYBLUE (-2400 2925);
FORCEPROP 1 LAST MATERIAL CHIP
J 0
(-2375 2875);
DISPLAY 0.617021 (-2375 2875);
PAINT SKYBLUE (-2375 2875);
FORCEPROP 1 LAST TOLERANCE 1%
J 0
(-2375 2925);
DISPLAY 0.617021 (-2375 2925);
PAINT SKYBLUE (-2375 2925);
FORCEPROP 1 LAST WATTAGE 1/16W
J 2
(-2400 2875);
DISPLAY 0.617021 (-2400 2875);
PAINT SKYBLUE (-2400 2875);
FORCEPROP 2 LAST CDS_LIB mstr_discrete
J 0
(-2375 3025);
PAINT MONO (-2375 3025);
DISPLAY INVISIBLE (-2375 3025);
FORCEPROP 2 LAST SEC_TYPE 0402
J 0
(-2425 3225);
DISPLAY 1.021277 (-2425 3225);
PAINT ORANGE (-2425 3225);
DISPLAY INVISIBLE (-2425 3225);
FORCEPROP 2 LAST SEC 1
J 0
(-2425 3225);
DISPLAY 0.680851 (-2425 3225);
PAINT MONO (-2425 3225);
DISPLAY INVISIBLE (-2425 3225);
FORCEPROP 2 LAST CDS_LOCATION R9P3
J 0
(-2425 3075);
DISPLAY 0.617021 (-2425 3075);
PAINT AQUA (-2425 3075);
DISPLAY INVISIBLE (-2425 3075);
FORCEPROP 1 LAST PATH I117
J 0
(-2425 3175);
DISPLAY 0.978723 (-2425 3175);
PAINT WHITE (-2425 3175);
DISPLAY INVISIBLE (-2425 3175);
FORCEADD RES..1
(-5200 2275);
FORCEPROP 1 LAST LOCATION R9N16
J 0
(-5250 2325);
DISPLAY 0.617021 (-5250 2325);
PAINT AQUA (-5250 2325);
FORCEPROP 1 LAST PART_NUMBER G21497-005
J 0
(-5350 2225);
DISPLAY 0.617021 (-5350 2225);
PAINT BLUE (-5350 2225);
FORCEPROP 1 LAST PACK_TYPE 0402
J 0
(-5125 2175);
DISPLAY 0.617021 (-5125 2175);
PAINT SKYBLUE (-5125 2175);
FORCEPROP 1 LAST TOLERANCE 5%
J 0
(-5250 2175);
DISPLAY 0.617021 (-5250 2175);
PAINT SKYBLUE (-5250 2175);
FORCEPROP 1 LAST VALUE 0.0
J 2
(-5300 2175);
DISPLAY 0.617021 (-5300 2175);
PAINT SKYBLUE (-5300 2175);
FORCEPROP 1 LAST WATTAGE 1/16W
J 2
(-5225 2125);
DISPLAY 0.617021 (-5225 2125);
PAINT SKYBLUE (-5225 2125);
FORCEPROP 1 LASTPIN (-5100 2275) $PN 2
J 0
(-5138 2287);
DISPLAY 0.617021 (-5138 2287);
PAINT ORANGE (-5138 2287);
FORCEPROP 1 LASTPIN (-5300 2275) $PN 1
J 0
(-5288 2287);
DISPLAY 0.617021 (-5288 2287);
PAINT ORANGE (-5288 2287);
FORCEPROP 1 LAST MATERIAL CHIP
J 0
(-5200 2125);
DISPLAY 0.617021 (-5200 2125);
PAINT SKYBLUE (-5200 2125);
FORCEPROP 2 LAST ROOM PVCCIN_CPU0_VR
J 0
(-5250 2375);
DISPLAY 1.361702 (-5250 2375);
PAINT ORANGE (-5250 2375);
DISPLAY INVISIBLE (-5250 2375);
FORCEPROP 1 LAST PATH I119
J 0
(-5250 2425);
DISPLAY 0.978723 (-5250 2425);
PAINT WHITE (-5250 2425);
DISPLAY INVISIBLE (-5250 2425);
FORCEPROP 2 LAST CDS_LOCATION R9N16
J 0
(-5250 2325);
DISPLAY 0.617021 (-5250 2325);
PAINT AQUA (-5250 2325);
DISPLAY INVISIBLE (-5250 2325);
FORCEPROP 2 LAST SEC 1
J 0
(-5250 2475);
PAINT MONO (-5250 2475);
DISPLAY INVISIBLE (-5250 2475);
FORCEPROP 2 LAST SEC_TYPE 0402
J 0
(-5250 2475);
DISPLAY 1.021277 (-5250 2475);
PAINT ORANGE (-5250 2475);
DISPLAY INVISIBLE (-5250 2475);
FORCEPROP 2 LAST CDS_LIB mstr_discrete
J 0
(-5200 2275);
PAINT ORANGE (-5200 2275);
DISPLAY INVISIBLE (-5200 2275);
FORCEADD OFFPAGE..2
(-1150 2725);
FORCEPROP 2 LAST $XR0 190 
J 0
(-961 2725);
DISPLAY 0.638298 (-961 2725);
PAINT MONO (-961 2725);
FORCEPROP 1 LAST COMMENT_BODY TRUE
J 0
(-1195 2630);
DISPLAY 1.170213 (-1195 2630);
PAINT PEACH (-1195 2630);
DISPLAY INVISIBLE (-1195 2630);
FORCEPROP 1 LAST OFFPAGE TRUE
J 0
(-825 2600);
DISPLAY 1.170213 (-825 2600);
PAINT GREEN (-825 2600);
DISPLAY INVISIBLE (-825 2600);
FORCEPROP 2 LAST PATH I12
J 0
(-975 2800);
DISPLAY 1.021277 (-975 2800);
PAINT ORANGE (-975 2800);
DISPLAY INVISIBLE (-975 2800);
FORCEPROP 2 LAST CDS_LIB mstr_standard
J 0
(-1150 2725);
PAINT ORANGE (-1150 2725);
DISPLAY INVISIBLE (-1150 2725);
FORCEPROP 2 LAST ROOM PVCCIN_CPU1_VR
J 0
(-1575 2800);
DISPLAY 1.361702 (-1575 2800);
PAINT WHITE (-1575 2800);
DISPLAY INVISIBLE (-1575 2800);
FORCEADD RES..2
(-4650 4400);
FORCEPROP 1 LAST MATERIAL CHIP
J 0
(-4610 4325);
DISPLAY 0.617021 (-4610 4325);
PAINT SKYBLUE (-4610 4325);
FORCEPROP 1 LASTPIN (-4650 4300) $PN 2
J 0
(-4645 4310);
DISPLAY 0.617021 (-4645 4310);
PAINT ORANGE (-4645 4310);
FORCEPROP 1 LAST LOCATION R9N14
J 0
(-4605 4525);
DISPLAY 0.617021 (-4605 4525);
PAINT AQUA (-4605 4525);
FORCEPROP 1 LAST VALUE 1.00K
J 0
(-4605 4475);
DISPLAY 0.617021 (-4605 4475);
PAINT SKYBLUE (-4605 4475);
FORCEPROP 1 LAST TOLERANCE 1%
J 0
(-4605 4425);
DISPLAY 0.617021 (-4605 4425);
PAINT SKYBLUE (-4605 4425);
FORCEPROP 1 LAST PART_NUMBER G21796-026
J 0
(-4610 4275);
DISPLAY 0.617021 (-4610 4275);
PAINT BLUE (-4610 4275);
FORCEPROP 1 LAST PACK_TYPE 0402
J 0
(-4610 4225);
DISPLAY 0.617021 (-4610 4225);
PAINT SKYBLUE (-4610 4225);
FORCEPROP 1 LAST WATTAGE 1/16W
J 0
(-4610 4375);
DISPLAY 0.617021 (-4610 4375);
PAINT SKYBLUE (-4610 4375);
FORCEPROP 1 LASTPIN (-4650 4500) $PN 1
J 0
(-4645 4462);
DISPLAY 0.617021 (-4645 4462);
PAINT ORANGE (-4645 4462);
FORCEPROP 0 LAST BOM_COST SM_CONTROLLER
J 0
(-4600 4725);
DISPLAY 1.021277 (-4600 4725);
PAINT ORANGE (-4600 4725);
DISPLAY INVISIBLE (-4600 4725);
FORCEPROP 2 LAST SEC_TYPE 0402
J 0
(-4600 4625);
DISPLAY 1.021277 (-4600 4625);
PAINT ORANGE (-4600 4625);
DISPLAY INVISIBLE (-4600 4625);
FORCEPROP 2 LAST SEC 1
J 0
(-4600 4625);
PAINT MONO (-4600 4625);
DISPLAY INVISIBLE (-4600 4625);
FORCEPROP 0 LAST ROOM BMC
J 0
(-4600 4625);
DISPLAY 0.617021 (-4600 4625);
PAINT ORANGE (-4600 4625);
DISPLAY INVISIBLE (-4600 4625);
FORCEPROP 1 LAST PATH I120
J 0
(-4600 4575);
DISPLAY 0.978723 (-4600 4575);
PAINT WHITE (-4600 4575);
DISPLAY INVISIBLE (-4600 4575);
FORCEPROP 2 LAST CDS_LOCATION R9N14
J 0
(-4605 4525);
DISPLAY 0.617021 (-4605 4525);
PAINT AQUA (-4605 4525);
DISPLAY INVISIBLE (-4605 4525);
FORCEPROP 2 LAST CDS_LIB mstr_discrete
J 0
(-4650 4400);
PAINT ORANGE (-4650 4400);
DISPLAY INVISIBLE (-4650 4400);
FORCEADD OFFPAGE..2
(-1150 2575);
FORCEPROP 2 LAST $XR0 210 
J 0
(-961 2575);
DISPLAY 0.638298 (-961 2575);
PAINT MONO (-961 2575);
FORCEPROP 1 LAST COMMENT_BODY TRUE
J 0
(-1195 2480);
DISPLAY 1.170213 (-1195 2480);
PAINT PEACH (-1195 2480);
DISPLAY INVISIBLE (-1195 2480);
FORCEPROP 1 LAST OFFPAGE TRUE
J 0
(-825 2450);
DISPLAY 1.170213 (-825 2450);
PAINT GREEN (-825 2450);
DISPLAY INVISIBLE (-825 2450);
FORCEPROP 2 LAST PATH I13
J 0
(-975 2650);
DISPLAY 1.021277 (-975 2650);
PAINT ORANGE (-975 2650);
DISPLAY INVISIBLE (-975 2650);
FORCEPROP 2 LAST CDS_LIB mstr_standard
J 0
(-1150 2575);
PAINT ORANGE (-1150 2575);
DISPLAY INVISIBLE (-1150 2575);
FORCEPROP 2 LAST ROOM PVCCIN_CPU1_VR
J 0
(-1575 2650);
DISPLAY 1.361702 (-1575 2650);
PAINT WHITE (-1575 2650);
DISPLAY INVISIBLE (-1575 2650);
FORCEADD PXE1610B..1
(-3825 2625);
FORCEPROP 2 LASTPIN (-4275 1975) $PN 42
J 2
(-4285 1985);
DISPLAY 0.617021 (-4285 1985);
PAINT ORANGE (-4285 1985);
FORCEPROP 2 LASTPIN (-4275 1925) $PN 37
J 2
(-4285 1935);
DISPLAY 0.617021 (-4285 1935);
PAINT ORANGE (-4285 1935);
FORCEPROP 2 LASTPIN (-4275 1875) $PN 38
J 2
(-4285 1885);
DISPLAY 0.617021 (-4285 1885);
PAINT ORANGE (-4285 1885);
FORCEPROP 2 LASTPIN (-4275 1825) $PN 44
J 2
(-4285 1835);
DISPLAY 0.617021 (-4285 1835);
PAINT ORANGE (-4285 1835);
FORCEPROP 2 LASTPIN (-4275 2175) $PN 46
J 2
(-4285 2185);
DISPLAY 0.617021 (-4285 2185);
PAINT ORANGE (-4285 2185);
FORCEPROP 2 LASTPIN (-4275 2225) $PN 45
J 2
(-4285 2235);
DISPLAY 0.617021 (-4285 2235);
PAINT ORANGE (-4285 2235);
FORCEPROP 2 LASTPIN (-4275 2575) $PN 21
J 2
(-4285 2585);
DISPLAY 0.617021 (-4285 2585);
PAINT ORANGE (-4285 2585);
FORCEPROP 2 LASTPIN (-4275 2525) $PN 22
J 2
(-4285 2535);
DISPLAY 0.617021 (-4285 2535);
PAINT ORANGE (-4285 2535);
FORCEPROP 2 LASTPIN (-4275 2475) $PN 35
J 2
(-4285 2485);
DISPLAY 0.617021 (-4285 2485);
PAINT ORANGE (-4285 2485);
FORCEPROP 2 LASTPIN (-4275 2425) $PN 36
J 2
(-4285 2435);
DISPLAY 0.617021 (-4285 2435);
PAINT ORANGE (-4285 2435);
FORCEPROP 2 LASTPIN (-3375 3025) $PN 13
J 0
(-3365 3035);
DISPLAY 0.617021 (-3365 3035);
PAINT ORANGE (-3365 3035);
FORCEPROP 2 LASTPIN (-3375 2925) $PN 19
J 0
(-3365 2935);
DISPLAY 0.617021 (-3365 2935);
PAINT ORANGE (-3365 2935);
FORCEPROP 2 LASTPIN (-3375 2825) $PN 48
J 0
(-3365 2835);
DISPLAY 0.617021 (-3365 2835);
PAINT ORANGE (-3365 2835);
FORCEPROP 2 LASTPIN (-3375 2775) $PN 18
J 0
(-3365 2785);
DISPLAY 0.617021 (-3365 2785);
PAINT ORANGE (-3365 2785);
FORCEPROP 2 LASTPIN (-3375 2725) $PN 15
J 0
(-3365 2735);
DISPLAY 0.617021 (-3365 2735);
PAINT ORANGE (-3365 2735);
FORCEPROP 2 LASTPIN (-3375 2675) $PN 16
J 0
(-3365 2685);
DISPLAY 0.617021 (-3365 2685);
PAINT ORANGE (-3365 2685);
FORCEPROP 2 LASTPIN (-3375 3325) $PN 20
J 0
(-3365 3335);
DISPLAY 0.617021 (-3365 3335);
PAINT ORANGE (-3365 3335);
FORCEPROP 2 LASTPIN (-3375 3275) $PN 14
J 0
(-3365 3285);
DISPLAY 0.617021 (-3365 3285);
PAINT ORANGE (-3365 3285);
FORCEPROP 2 LASTPIN (-3375 3125) $PN 40
J 0
(-3365 3135);
DISPLAY 0.617021 (-3365 3135);
PAINT ORANGE (-3365 3135);
FORCEPROP 2 LASTPIN (-3375 2525) $PN 7
J 0
(-3365 2535);
DISPLAY 0.617021 (-3365 2535);
PAINT ORANGE (-3365 2535);
FORCEPROP 2 LASTPIN (-3375 2425) $PN 5
J 0
(-3365 2435);
DISPLAY 0.617021 (-3365 2435);
PAINT ORANGE (-3365 2435);
FORCEPROP 2 LASTPIN (-3375 2475) $PN 6
J 0
(-3365 2485);
DISPLAY 0.617021 (-3365 2485);
PAINT ORANGE (-3365 2485);
FORCEPROP 2 LASTPIN (-3375 2325) $PN 3
J 0
(-3365 2335);
DISPLAY 0.617021 (-3365 2335);
PAINT ORANGE (-3365 2335);
FORCEPROP 2 LASTPIN (-3375 2375) $PN 4
J 0
(-3365 2385);
DISPLAY 0.617021 (-3365 2385);
PAINT ORANGE (-3365 2385);
FORCEPROP 2 LASTPIN (-3375 2275) $PN 2
J 0
(-3365 2285);
DISPLAY 0.617021 (-3365 2285);
PAINT ORANGE (-3365 2285);
FORCEPROP 2 LASTPIN (-3375 2175) $PN 8
J 0
(-3365 2185);
DISPLAY 0.617021 (-3365 2185);
PAINT ORANGE (-3365 2185);
FORCEPROP 2 LASTPIN (-3375 2075) $PN 9
J 0
(-3365 2085);
DISPLAY 0.617021 (-3365 2085);
PAINT ORANGE (-3365 2085);
FORCEPROP 1 LAST MATERIAL IC
J 0
(-4225 3550);
DISPLAY 0.617021 (-4225 3550);
PAINT SKYBLUE (-4225 3550);
FORCEPROP 2 LASTPIN (-4275 2725) $PN 32
J 2
(-4285 2735);
DISPLAY 0.617021 (-4285 2735);
PAINT ORANGE (-4285 2735);
FORCEPROP 2 LASTPIN (-4275 2275) $PN 12
J 2
(-4285 2285);
DISPLAY 0.617021 (-4285 2285);
PAINT ORANGE (-4285 2285);
FORCEPROP 2 LASTPIN (-4275 1775) $PN 41
J 2
(-4285 1785);
DISPLAY 0.617021 (-4285 1785);
PAINT ORANGE (-4285 1785);
FORCEPROP 2 LASTPIN (-3375 3175) $PN 39
J 0
(-3365 3185);
DISPLAY 0.617021 (-3365 3185);
PAINT ORANGE (-3365 3185);
FORCEPROP 2 LASTPIN (-3375 2575) $PN 1
J 0
(-3365 2585);
DISPLAY 0.617021 (-3365 2585);
PAINT ORANGE (-3365 2585);
FORCEPROP 2 LASTPIN (-3375 3375) $PN 11
J 0
(-3365 3385);
DISPLAY 0.617021 (-3365 3385);
PAINT ORANGE (-3365 3385);
FORCEPROP 2 LASTPIN (-3375 1875) $PN 49
J 0
(-3365 1885);
DISPLAY 0.617021 (-3365 1885);
PAINT ORANGE (-3365 1885);
FORCEPROP 2 LASTPIN (-4275 2875) $PN 26
J 2
(-4285 2885);
DISPLAY 0.617021 (-4285 2885);
PAINT ORANGE (-4285 2885);
FORCEPROP 2 LASTPIN (-4275 2925) $PN 24
J 2
(-4285 2935);
DISPLAY 0.617021 (-4285 2935);
PAINT ORANGE (-4285 2935);
FORCEPROP 2 LASTPIN (-4275 3025) $PN 31
J 2
(-4285 3035);
DISPLAY 0.617021 (-4285 3035);
PAINT ORANGE (-4285 3035);
FORCEPROP 2 LASTPIN (-4275 3225) $PN 23
J 2
(-4285 3235);
DISPLAY 0.617021 (-4285 3235);
PAINT ORANGE (-4285 3235);
FORCEPROP 2 LASTPIN (-4275 3325) $PN 17
J 2
(-4285 3335);
DISPLAY 0.617021 (-4285 3335);
PAINT ORANGE (-4285 3335);
FORCEPROP 2 LASTPIN (-4275 3425) $PN 47
J 2
(-4285 3435);
DISPLAY 0.617021 (-4285 3435);
PAINT ORANGE (-4285 3435);
FORCEPROP 2 LASTPIN (-4275 2975) $PN 33
J 2
(-4285 2985);
DISPLAY 0.617021 (-4285 2985);
PAINT ORANGE (-4285 2985);
FORCEPROP 2 LASTPIN (-4275 2075) $PN 10
J 2
(-4285 2085);
DISPLAY 0.617021 (-4285 2085);
PAINT ORANGE (-4285 2085);
FORCEPROP 2 LASTPIN (-4275 2325) $PN 43
J 2
(-4285 2335);
DISPLAY 0.617021 (-4285 2335);
PAINT ORANGE (-4285 2335);
FORCEPROP 1 LAST LOCATION EU1C2
J 0
(-4225 3600);
DISPLAY 0.617021 (-4225 3600);
PAINT AQUA (-4225 3600);
FORCEPROP 2 LASTPIN (-4275 3175) $PN 25
J 2
(-4285 3185);
DISPLAY 0.617021 (-4285 3185);
PAINT ORANGE (-4285 3185);
FORCEPROP 2 LASTPIN (-4275 3075) $PN 29
J 2
(-4285 3085);
DISPLAY 0.617021 (-4285 3085);
PAINT ORANGE (-4285 3085);
FORCEPROP 2 LASTPIN (-4275 3125) $PN 27
J 2
(-4285 3135);
DISPLAY 0.617021 (-4285 3135);
PAINT ORANGE (-4285 3135);
FORCEPROP 2 LASTPIN (-4275 2675) $PN 34
J 2
(-4285 2685);
DISPLAY 0.617021 (-4285 2685);
PAINT ORANGE (-4285 2685);
FORCEPROP 2 LASTPIN (-4275 2825) $PN 28
J 2
(-4285 2835);
DISPLAY 0.617021 (-4285 2835);
PAINT ORANGE (-4285 2835);
FORCEPROP 2 LASTPIN (-4275 2775) $PN 30
J 2
(-4285 2785);
DISPLAY 0.617021 (-4285 2785);
PAINT ORANGE (-4285 2785);
FORCEPROP 1 LAST PART_NUMBER H79206-001
J 0
(-4225 1675);
DISPLAY 0.617021 (-4225 1675);
PAINT BLUE (-4225 1675);
FORCEPROP 1 LAST PATH I130
J 0
(-3725 3551);
PAINT WHITE (-3725 3551);
DISPLAY INVISIBLE (-3725 3551);
FORCEPROP 2 LAST CDS_LIB mstr_controller
J 0
(-3825 2625);
PAINT ORANGE (-3825 2625);
DISPLAY INVISIBLE (-3825 2625);
FORCEPROP 1 LAST CDS_LMAN_SYM_OUTLINE -400,900,400,-900
J 0
(-3825 2625);
DISPLAY 0.468085 (-3825 2625);
PAINT GREEN (-3825 2625);
DISPLAY INVISIBLE (-3825 2625);
FORCEPROP 1 LAST PACK_TYPE QFN
J 0
(-4225 3650);
PAINT SKYBLUE (-4225 3650);
DISPLAY INVISIBLE (-4225 3650);
FORCEPROP 2 LAST SEC_TYPE QFN
J 0
(-4225 3650);
DISPLAY 1.021277 (-4225 3650);
PAINT ORANGE (-4225 3650);
DISPLAY INVISIBLE (-4225 3650);
FORCEPROP 2 LAST SEC 1
J 0
(-4225 3650);
DISPLAY 0.680851 (-4225 3650);
PAINT MONO (-4225 3650);
DISPLAY INVISIBLE (-4225 3650);
FORCEPROP 2 LAST CDS_LOCATION EU1C2
J 0
(-4225 3600);
DISPLAY 0.617021 (-4225 3600);
PAINT AQUA (-4225 3600);
DISPLAY INVISIBLE (-4225 3600);
FORCEADD SC22P50V2JN-4GP..1
R 1
(-6775 3350);
FORCEPROP 2 LAST ATTRIBUTE 22PF
J 0
(-6950 3125);
DISPLAY 0.638298 (-6950 3125);
PAINT GREEN (-6950 3125);
FORCEPROP 2 LAST RATED 50V
J 0
(-6950 3025);
DISPLAY 0.638298 (-6950 3025);
PAINT GREEN (-6950 3025);
FORCEPROP 2 LAST TYPE NPO
J 0
(-6950 2975);
DISPLAY 0.638298 (-6950 2975);
PAINT GREEN (-6950 2975);
FORCEPROP 2 LAST TOLERANCE 5%
J 0
(-6950 3075);
DISPLAY 0.638298 (-6950 3075);
PAINT GREEN (-6950 3075);
FORCEPROP 2 LAST PACK_SIZE 0402
J 0
(-6800 3125);
DISPLAY 0.638298 (-6800 3125);
PAINT GREEN (-6800 3125);
FORCEPROP 1 LAST LOCATION CF7
J 0
(-6930 3225);
DISPLAY 0.617021 (-6930 3225);
PAINT GREEN (-6930 3225);
FORCEPROP 1 LAST VALUE SC22P50V2JN-4GP
J 0
(-6950 3175);
DISPLAY 0.617021 (-6950 3175);
PAINT GREEN (-6950 3175);
FORCEPROP 0 LAST GROUP POWER_FAIR
J 0
(-6906 3274);
DISPLAY 0.638298 (-6906 3274);
PAINT BROWN (-6906 3274);
DISPLAY BOTH (-6906 3274);
FORCEPROP 1 LAST PACK_TYPE SMD-BCG
R 1
J 0
(-6775 3350);
DISPLAY 0.617021 (-6775 3350);
PAINT GREEN (-6775 3350);
DISPLAY INVISIBLE (-6775 3350);
FORCEPROP 1 LAST PART_NUMBER 78.22034.1FL
R 1
J 0
(-6775 3350);
DISPLAY 0.617021 (-6775 3350);
PAINT GREEN (-6775 3350);
DISPLAY INVISIBLE (-6775 3350);
FORCEPROP 1 LAST CDS_LMAN_SYM_OUTLINE -50,25,50,-25
R 1
J 0
(-6775 3350);
DISPLAY 0.468085 (-6775 3350);
PAINT GREEN (-6775 3350);
DISPLAY INVISIBLE (-6775 3350);
FORCEPROP 1 LAST PATH I137
R 1
J 0
(-6775 3350);
DISPLAY 0.617021 (-6775 3350);
PAINT GREEN (-6775 3350);
DISPLAY INVISIBLE (-6775 3350);
FORCEPROP 2 LAST CDS_LIB w_hdl
J 0
(-6775 3350);
PAINT MONO (-6775 3350);
DISPLAY INVISIBLE (-6775 3350);
FORCEADD SC22P50V2JN-4GP..1
R 1
(-6375 3350);
FORCEPROP 2 LAST TYPE NPO
J 0
(-6525 2975);
DISPLAY 0.638298 (-6525 2975);
PAINT GREEN (-6525 2975);
FORCEPROP 2 LAST RATED 50V
J 0
(-6525 3025);
DISPLAY 0.638298 (-6525 3025);
PAINT GREEN (-6525 3025);
FORCEPROP 2 LASTPIN (-6300 3350) $PN 2
J 0
(-6290 3360);
DISPLAY 0.638298 (-6290 3360);
PAINT ORANGE (-6290 3360);
FORCEPROP 2 LASTPIN (-6450 3350) $PN 1
J 2
(-6460 3360);
DISPLAY 0.638298 (-6460 3360);
PAINT ORANGE (-6460 3360);
FORCEPROP 1 LAST LOCATION CF8
J 0
(-6530 3225);
DISPLAY 0.617021 (-6530 3225);
PAINT GREEN (-6530 3225);
FORCEPROP 2 LAST TOLERANCE 5%
J 0
(-6525 3075);
DISPLAY 0.638298 (-6525 3075);
PAINT GREEN (-6525 3075);
FORCEPROP 2 LAST ATTRIBUTE 22PF
J 0
(-6525 3125);
DISPLAY 0.638298 (-6525 3125);
PAINT GREEN (-6525 3125);
FORCEPROP 2 LAST PACK_SIZE 0402
J 0
(-6350 3125);
DISPLAY 0.638298 (-6350 3125);
PAINT GREEN (-6350 3125);
FORCEPROP 1 LAST VALUE SC22P50V2JN-4GP
J 0
(-6525 3175);
DISPLAY 0.617021 (-6525 3175);
PAINT GREEN (-6525 3175);
FORCEPROP 0 LAST GROUP POWER_FAIR
J 0
(-6506 3274);
DISPLAY 0.638298 (-6506 3274);
PAINT BROWN (-6506 3274);
DISPLAY BOTH (-6506 3274);
FORCEPROP 2 LAST SEC_TYPE SMD-BCG
J 0
(-6475 3425);
DISPLAY 1.021277 (-6475 3425);
PAINT ORANGE (-6475 3425);
DISPLAY INVISIBLE (-6475 3425);
FORCEPROP 2 LAST SEC 1
J 0
(-6475 3425);
DISPLAY 0.680851 (-6475 3425);
PAINT MONO (-6475 3425);
DISPLAY INVISIBLE (-6475 3425);
FORCEPROP 1 LAST PACK_TYPE SMD-BCG
R 1
J 0
(-6375 3350);
DISPLAY 0.617021 (-6375 3350);
PAINT GREEN (-6375 3350);
DISPLAY INVISIBLE (-6375 3350);
FORCEPROP 1 LAST CDS_LMAN_SYM_OUTLINE -50,25,50,-25
R 1
J 0
(-6375 3350);
DISPLAY 0.468085 (-6375 3350);
PAINT GREEN (-6375 3350);
DISPLAY INVISIBLE (-6375 3350);
FORCEPROP 2 LAST CDS_LIB w_hdl
J 0
(-6375 3350);
PAINT MONO (-6375 3350);
DISPLAY INVISIBLE (-6375 3350);
FORCEPROP 1 LAST PATH I138
R 1
J 0
(-6375 3350);
DISPLAY 0.617021 (-6375 3350);
PAINT GREEN (-6375 3350);
DISPLAY INVISIBLE (-6375 3350);
FORCEPROP 1 LAST PART_NUMBER 78.22034.1FL
R 1
J 0
(-6375 3350);
DISPLAY 0.617021 (-6375 3350);
PAINT GREEN (-6375 3350);
DISPLAY INVISIBLE (-6375 3350);
FORCEADD SC22P50V2JN-4GP..1
R 1
(-6000 3350);
FORCEPROP 2 LAST PACK_SIZE 0402
J 0
(-5950 3125);
DISPLAY 0.638298 (-5950 3125);
PAINT GREEN (-5950 3125);
FORCEPROP 2 LAST TYPE NPO
J 0
(-6125 2975);
DISPLAY 0.638298 (-6125 2975);
PAINT GREEN (-6125 2975);
FORCEPROP 2 LAST RATED 50V
J 0
(-6125 3025);
DISPLAY 0.638298 (-6125 3025);
PAINT GREEN (-6125 3025);
FORCEPROP 2 LAST TOLERANCE 5%
J 0
(-6125 3075);
DISPLAY 0.638298 (-6125 3075);
PAINT GREEN (-6125 3075);
FORCEPROP 2 LAST ATTRIBUTE 22PF
J 0
(-6125 3125);
DISPLAY 0.638298 (-6125 3125);
PAINT GREEN (-6125 3125);
FORCEPROP 1 LAST LOCATION CF9
J 0
(-6130 3225);
DISPLAY 0.617021 (-6130 3225);
PAINT GREEN (-6130 3225);
FORCEPROP 1 LAST VALUE SC22P50V2JN-4GP
J 0
(-6125 3175);
DISPLAY 0.617021 (-6125 3175);
PAINT GREEN (-6125 3175);
FORCEPROP 0 LAST GROUP POWER_FAIR
J 0
(-6131 3274);
DISPLAY 0.638298 (-6131 3274);
PAINT BROWN (-6131 3274);
DISPLAY BOTH (-6131 3274);
FORCEPROP 1 LAST CDS_LMAN_SYM_OUTLINE -50,25,50,-25
R 1
J 0
(-6000 3350);
DISPLAY 0.468085 (-6000 3350);
PAINT GREEN (-6000 3350);
DISPLAY INVISIBLE (-6000 3350);
FORCEPROP 2 LAST CDS_LIB w_hdl
J 0
(-6000 3350);
PAINT MONO (-6000 3350);
DISPLAY INVISIBLE (-6000 3350);
FORCEPROP 1 LAST PATH I139
R 1
J 0
(-6000 3350);
DISPLAY 0.617021 (-6000 3350);
PAINT GREEN (-6000 3350);
DISPLAY INVISIBLE (-6000 3350);
FORCEPROP 1 LAST PACK_TYPE SMD-BCG
R 1
J 0
(-6000 3350);
DISPLAY 0.617021 (-6000 3350);
PAINT GREEN (-6000 3350);
DISPLAY INVISIBLE (-6000 3350);
FORCEPROP 1 LAST PART_NUMBER 78.22034.1FL
R 1
J 0
(-6000 3350);
DISPLAY 0.617021 (-6000 3350);
PAINT GREEN (-6000 3350);
DISPLAY INVISIBLE (-6000 3350);
FORCEADD OFFPAGE..2
(-1150 2475);
FORCEPROP 2 LAST $XR0 207 
J 0
(-961 2475);
DISPLAY 0.638298 (-961 2475);
PAINT MONO (-961 2475);
FORCEPROP 1 LAST COMMENT_BODY TRUE
J 0
(-1195 2380);
DISPLAY 1.170213 (-1195 2380);
PAINT PEACH (-1195 2380);
DISPLAY INVISIBLE (-1195 2380);
FORCEPROP 1 LAST OFFPAGE TRUE
J 0
(-825 2350);
DISPLAY 1.170213 (-825 2350);
PAINT GREEN (-825 2350);
DISPLAY INVISIBLE (-825 2350);
FORCEPROP 2 LAST PATH I14
J 0
(-950 2525);
DISPLAY 1.021277 (-950 2525);
PAINT ORANGE (-950 2525);
DISPLAY INVISIBLE (-950 2525);
FORCEPROP 2 LAST CDS_LIB mstr_standard
J 0
(-1150 2475);
PAINT ORANGE (-1150 2475);
DISPLAY INVISIBLE (-1150 2475);
FORCEPROP 2 LAST ROOM PVCCIN_CPU1_VR
J 0
(-1575 2550);
DISPLAY 1.361702 (-1575 2550);
PAINT WHITE (-1575 2550);
DISPLAY INVISIBLE (-1575 2550);
FORCEADD SC22P50V2JN-4GP..1
R 1
(-5550 3350);
FORCEPROP 2 LAST RATED 50V
J 0
(-5700 3025);
DISPLAY 0.638298 (-5700 3025);
PAINT GREEN (-5700 3025);
FORCEPROP 2 LAST ATTRIBUTE 22PF
J 0
(-5700 3125);
DISPLAY 0.638298 (-5700 3125);
PAINT GREEN (-5700 3125);
FORCEPROP 2 LAST TYPE NPO
J 0
(-5700 2975);
DISPLAY 0.638298 (-5700 2975);
PAINT GREEN (-5700 2975);
FORCEPROP 2 LAST TOLERANCE 5%
J 0
(-5700 3075);
DISPLAY 0.638298 (-5700 3075);
PAINT GREEN (-5700 3075);
FORCEPROP 1 LAST LOCATION CF10
J 0
(-5705 3225);
DISPLAY 0.617021 (-5705 3225);
PAINT GREEN (-5705 3225);
FORCEPROP 2 LAST PACK_SIZE 0402
J 0
(-5550 3125);
DISPLAY 0.638298 (-5550 3125);
PAINT GREEN (-5550 3125);
FORCEPROP 1 LAST VALUE SC22P50V2JN-4GP
J 0
(-5700 3175);
DISPLAY 0.617021 (-5700 3175);
PAINT GREEN (-5700 3175);
FORCEPROP 0 LAST GROUP POWER_FAIR
J 0
(-5706 3274);
DISPLAY 0.638298 (-5706 3274);
PAINT BROWN (-5706 3274);
DISPLAY BOTH (-5706 3274);
FORCEPROP 2 LAST CDS_LIB w_hdl
J 0
(-5550 3350);
PAINT MONO (-5550 3350);
DISPLAY INVISIBLE (-5550 3350);
FORCEPROP 1 LAST PATH I140
R 1
J 0
(-5550 3350);
DISPLAY 0.617021 (-5550 3350);
PAINT GREEN (-5550 3350);
DISPLAY INVISIBLE (-5550 3350);
FORCEPROP 1 LAST CDS_LMAN_SYM_OUTLINE -50,25,50,-25
R 1
J 0
(-5550 3350);
DISPLAY 0.468085 (-5550 3350);
PAINT GREEN (-5550 3350);
DISPLAY INVISIBLE (-5550 3350);
FORCEPROP 1 LAST PART_NUMBER 78.22034.1FL
R 1
J 0
(-5550 3350);
DISPLAY 0.617021 (-5550 3350);
PAINT GREEN (-5550 3350);
DISPLAY INVISIBLE (-5550 3350);
FORCEPROP 1 LAST PACK_TYPE SMD-BCG
R 1
J 0
(-5550 3350);
DISPLAY 0.617021 (-5550 3350);
PAINT GREEN (-5550 3350);
DISPLAY INVISIBLE (-5550 3350);
FORCEADD SC22P50V2JN-4GP..1
R 1
(-5100 3350);
FORCEPROP 2 LAST TOLERANCE 5%
J 0
(-5250 3075);
DISPLAY 0.638298 (-5250 3075);
PAINT GREEN (-5250 3075);
FORCEPROP 2 LAST ATTRIBUTE 22PF
J 0
(-5250 3125);
DISPLAY 0.638298 (-5250 3125);
PAINT GREEN (-5250 3125);
FORCEPROP 1 LAST LOCATION CF11
J 0
(-5255 3225);
DISPLAY 0.617021 (-5255 3225);
PAINT GREEN (-5255 3225);
FORCEPROP 0 LAST GROUP POWER_FAIR
J 0
(-5206 3274);
DISPLAY 0.638298 (-5206 3274);
PAINT BROWN (-5206 3274);
DISPLAY BOTH (-5206 3274);
FORCEPROP 1 LAST VALUE SC22P50V2JN-4GP
J 0
(-5250 3175);
DISPLAY 0.617021 (-5250 3175);
PAINT GREEN (-5250 3175);
FORCEPROP 2 LAST PACK_SIZE 0402
J 0
(-5100 3125);
DISPLAY 0.638298 (-5100 3125);
PAINT GREEN (-5100 3125);
FORCEPROP 2 LAST RATED 50V
J 0
(-5250 3025);
DISPLAY 0.638298 (-5250 3025);
PAINT GREEN (-5250 3025);
FORCEPROP 2 LAST TYPE NPO
J 0
(-5250 2975);
DISPLAY 0.638298 (-5250 2975);
PAINT GREEN (-5250 2975);
FORCEPROP 1 LAST PART_NUMBER 78.22034.1FL
R 1
J 0
(-5100 3350);
DISPLAY 0.617021 (-5100 3350);
PAINT GREEN (-5100 3350);
DISPLAY INVISIBLE (-5100 3350);
FORCEPROP 1 LAST PACK_TYPE SMD-BCG
R 1
J 0
(-5100 3350);
DISPLAY 0.617021 (-5100 3350);
PAINT GREEN (-5100 3350);
DISPLAY INVISIBLE (-5100 3350);
FORCEPROP 1 LAST CDS_LMAN_SYM_OUTLINE -50,25,50,-25
R 1
J 0
(-5100 3350);
DISPLAY 0.468085 (-5100 3350);
PAINT GREEN (-5100 3350);
DISPLAY INVISIBLE (-5100 3350);
FORCEPROP 1 LAST PATH I141
R 1
J 0
(-5100 3350);
DISPLAY 0.617021 (-5100 3350);
PAINT GREEN (-5100 3350);
DISPLAY INVISIBLE (-5100 3350);
FORCEPROP 2 LAST CDS_LIB w_hdl
J 0
(-5100 3350);
PAINT MONO (-5100 3350);
DISPLAY INVISIBLE (-5100 3350);
FORCEADD SC22P50V2JN-4GP..1
R 1
(-6525 1275);
FORCEPROP 1 LAST LOCATION CF12
J 0
(-6680 1150);
DISPLAY 0.617021 (-6680 1150);
PAINT GREEN (-6680 1150);
FORCEPROP 2 LAST RATED 50V
J 0
(-6675 950);
DISPLAY 0.638298 (-6675 950);
PAINT GREEN (-6675 950);
FORCEPROP 2 LAST TOLERANCE 5%
J 0
(-6675 1000);
DISPLAY 0.638298 (-6675 1000);
PAINT GREEN (-6675 1000);
FORCEPROP 2 LAST ATTRIBUTE 22PF
J 0
(-6675 1050);
DISPLAY 0.638298 (-6675 1050);
PAINT GREEN (-6675 1050);
FORCEPROP 0 LAST GROUP POWER_FAIR
J 0
(-6681 1199);
DISPLAY 0.638298 (-6681 1199);
PAINT BROWN (-6681 1199);
DISPLAY BOTH (-6681 1199);
FORCEPROP 1 LAST VALUE SC22P50V2JN-4GP
J 0
(-6675 1100);
DISPLAY 0.617021 (-6675 1100);
PAINT GREEN (-6675 1100);
FORCEPROP 2 LAST TYPE NPO
J 0
(-6475 1050);
DISPLAY 0.638298 (-6475 1050);
PAINT GREEN (-6475 1050);
FORCEPROP 2 LAST PACK_SIZE 0402
J 0
(-6475 1000);
DISPLAY 0.638298 (-6475 1000);
PAINT GREEN (-6475 1000);
FORCEPROP 1 LAST PACK_TYPE SMD-BCG
R 1
J 0
(-6525 1275);
DISPLAY 0.617021 (-6525 1275);
PAINT GREEN (-6525 1275);
DISPLAY INVISIBLE (-6525 1275);
FORCEPROP 1 LAST PART_NUMBER 78.22034.1FL
R 1
J 0
(-6525 1275);
DISPLAY 0.617021 (-6525 1275);
PAINT GREEN (-6525 1275);
DISPLAY INVISIBLE (-6525 1275);
FORCEPROP 1 LAST CDS_LMAN_SYM_OUTLINE -50,25,50,-25
R 1
J 0
(-6525 1275);
DISPLAY 0.468085 (-6525 1275);
PAINT GREEN (-6525 1275);
DISPLAY INVISIBLE (-6525 1275);
FORCEPROP 1 LAST PATH I142
R 1
J 0
(-6525 1275);
DISPLAY 0.617021 (-6525 1275);
PAINT GREEN (-6525 1275);
DISPLAY INVISIBLE (-6525 1275);
FORCEPROP 2 LAST CDS_LIB w_hdl
J 0
(-6525 1275);
PAINT MONO (-6525 1275);
DISPLAY INVISIBLE (-6525 1275);
FORCEADD RES..1
(-6500 1425);
FORCEPROP 1 LAST TOLERANCE 0.1%
J 0
(-6400 1575);
DISPLAY 0.617021 (-6400 1575);
PAINT SKYBLUE (-6400 1575);
FORCEPROP 1 LAST PACK_TYPE 0402
J 0
(-6425 1525);
DISPLAY 0.617021 (-6425 1525);
PAINT SKYBLUE (-6425 1525);
FORCEPROP 1 LAST LOCATION RF12
J 0
(-6650 1575);
DISPLAY 0.617021 (-6650 1575);
PAINT AQUA (-6650 1575);
FORCEPROP 0 LAST FAIR_SS 064.1101D.M001
J 0
(-6650 1325);
DISPLAY 0.638298 (-6650 1325);
PAINT BROWN (-6650 1325);
DISPLAY BOTH (-6650 1325);
FORCEPROP 0 LAST GROUP POWER_FAIR
J 0
(-6650 1375);
DISPLAY 0.638298 (-6650 1375);
PAINT BROWN (-6650 1375);
DISPLAY BOTH (-6650 1375);
FORCEPROP 1 LAST PART_NUMBER G85996-004
J 0
(-6650 1525);
DISPLAY 0.617021 (-6650 1525);
PAINT BLUE (-6650 1525);
FORCEPROP 1 LAST VALUE 1.0K
J 2
(-6425 1575);
DISPLAY 0.617021 (-6425 1575);
PAINT SKYBLUE (-6425 1575);
FORCEPROP 1 LASTPIN (-6600 1425) $PN 1
J 0
(-6588 1437);
DISPLAY 0.787234 (-6588 1437);
PAINT ORANGE (-6588 1437);
FORCEPROP 1 LAST WATTAGE 1/16W
J 2
(-6500 1475);
DISPLAY 0.617021 (-6500 1475);
PAINT SKYBLUE (-6500 1475);
FORCEPROP 1 LASTPIN (-6400 1425) $PN 2
J 0
(-6438 1437);
DISPLAY 0.787234 (-6438 1437);
PAINT ORANGE (-6438 1437);
FORCEPROP 1 LAST MATERIAL CHIP
J 0
(-6450 1475);
DISPLAY 0.617021 (-6450 1475);
PAINT SKYBLUE (-6450 1475);
FORCEPROP 2 LAST SEC_TYPE 0402
J 0
(-6550 1625);
DISPLAY 1.021277 (-6550 1625);
PAINT ORANGE (-6550 1625);
DISPLAY INVISIBLE (-6550 1625);
FORCEPROP 0 LAST SEC 1
J 0
(-6425 1575);
DISPLAY 0.680851 (-6425 1575);
PAINT MONO (-6425 1575);
DISPLAY INVISIBLE (-6425 1575);
FORCEPROP 1 LAST PATH I149
J 0
(-6550 1575);
DISPLAY 0.978723 (-6550 1575);
PAINT WHITE (-6550 1575);
DISPLAY INVISIBLE (-6550 1575);
FORCEPROP 2 LAST CDS_LIB mstr_discrete
J 0
(-6500 1425);
PAINT MONO (-6500 1425);
DISPLAY INVISIBLE (-6500 1425);
FORCEPROP 0 LAST ROOM SB
J 0
(-6450 1650);
DISPLAY 1.021277 (-6450 1650);
PAINT ORANGE (-6450 1650);
DISPLAY INVISIBLE (-6450 1650);
FORCEADD OFFPAGE..2
(-1150 2525);
FORCEPROP 2 LAST $XR0 207 
J 0
(-961 2525);
DISPLAY 0.638298 (-961 2525);
PAINT MONO (-961 2525);
FORCEPROP 1 LAST COMMENT_BODY TRUE
J 0
(-1195 2430);
DISPLAY 1.170213 (-1195 2430);
PAINT PEACH (-1195 2430);
DISPLAY INVISIBLE (-1195 2430);
FORCEPROP 1 LAST OFFPAGE TRUE
J 0
(-825 2400);
DISPLAY 1.170213 (-825 2400);
PAINT GREEN (-825 2400);
DISPLAY INVISIBLE (-825 2400);
FORCEPROP 2 LAST PATH I15
J 0
(-950 2575);
DISPLAY 1.021277 (-950 2575);
PAINT ORANGE (-950 2575);
DISPLAY INVISIBLE (-950 2575);
FORCEPROP 2 LAST CDS_LIB mstr_standard
J 0
(-1150 2525);
PAINT ORANGE (-1150 2525);
DISPLAY INVISIBLE (-1150 2525);
FORCEPROP 2 LAST ROOM PVCCIN_CPU1_VR
J 0
(-1575 2600);
DISPLAY 1.361702 (-1575 2600);
PAINT WHITE (-1575 2600);
DISPLAY INVISIBLE (-1575 2600);
FORCEADD RES..1
(-6775 3500);
FORCEPROP 1 LAST TOLERANCE 0.1%
J 0
(-6725 3650);
DISPLAY 0.617021 (-6725 3650);
PAINT SKYBLUE (-6725 3650);
FORCEPROP 1 LAST PACK_TYPE 0402
J 0
(-6700 3600);
DISPLAY 0.617021 (-6700 3600);
PAINT SKYBLUE (-6700 3600);
FORCEPROP 1 LAST LOCATION RF7
J 0
(-6925 3650);
DISPLAY 0.617021 (-6925 3650);
PAINT AQUA (-6925 3650);
FORCEPROP 1 LAST MATERIAL CHIP
J 0
(-6700 3550);
DISPLAY 0.617021 (-6700 3550);
PAINT SKYBLUE (-6700 3550);
FORCEPROP 1 LASTPIN (-6875 3500) $PN 1
J 0
(-6863 3512);
DISPLAY 0.787234 (-6863 3512);
PAINT ORANGE (-6863 3512);
FORCEPROP 0 LAST GROUP POWER_FAIR
J 0
(-6900 3450);
DISPLAY 0.638298 (-6900 3450);
PAINT BROWN (-6900 3450);
DISPLAY BOTH (-6900 3450);
FORCEPROP 1 LAST VALUE 1.0K
J 2
(-6750 3650);
DISPLAY 0.617021 (-6750 3650);
PAINT SKYBLUE (-6750 3650);
FORCEPROP 1 LAST PART_NUMBER G85996-004
J 0
(-6925 3600);
DISPLAY 0.617021 (-6925 3600);
PAINT BLUE (-6925 3600);
FORCEPROP 1 LASTPIN (-6675 3500) $PN 2
J 0
(-6713 3512);
DISPLAY 0.787234 (-6713 3512);
PAINT ORANGE (-6713 3512);
FORCEPROP 0 LAST FAIR_SS 064.9530D.M001
J 0
(-6900 3400);
DISPLAY 0.638298 (-6900 3400);
PAINT BROWN (-6900 3400);
DISPLAY BOTH (-6900 3400);
FORCEPROP 1 LAST WATTAGE 1/16W
J 2
(-6800 3550);
DISPLAY 0.617021 (-6800 3550);
PAINT SKYBLUE (-6800 3550);
FORCEPROP 1 LAST PATH I150
J 0
(-6825 3650);
DISPLAY 0.978723 (-6825 3650);
PAINT WHITE (-6825 3650);
DISPLAY INVISIBLE (-6825 3650);
FORCEPROP 2 LAST CDS_LIB mstr_discrete
J 0
(-6775 3500);
PAINT MONO (-6775 3500);
DISPLAY INVISIBLE (-6775 3500);
FORCEPROP 0 LAST ROOM SB
J 0
(-6725 3725);
DISPLAY 1.021277 (-6725 3725);
PAINT ORANGE (-6725 3725);
DISPLAY INVISIBLE (-6725 3725);
FORCEPROP 0 LAST SEC 1
J 0
(-6700 3650);
DISPLAY 0.680851 (-6700 3650);
PAINT MONO (-6700 3650);
DISPLAY INVISIBLE (-6700 3650);
FORCEPROP 2 LAST SEC_TYPE 0402
J 0
(-6825 3700);
DISPLAY 1.021277 (-6825 3700);
PAINT ORANGE (-6825 3700);
DISPLAY INVISIBLE (-6825 3700);
FORCEADD RES..1
(-6375 3500);
FORCEPROP 1 LAST TOLERANCE 0.1%
J 0
(-6325 3650);
DISPLAY 0.617021 (-6325 3650);
PAINT SKYBLUE (-6325 3650);
FORCEPROP 1 LAST VALUE 1.0K
J 2
(-6350 3650);
DISPLAY 0.617021 (-6350 3650);
PAINT SKYBLUE (-6350 3650);
FORCEPROP 1 LAST LOCATION RF8
J 0
(-6525 3650);
DISPLAY 0.617021 (-6525 3650);
PAINT AQUA (-6525 3650);
FORCEPROP 1 LAST PART_NUMBER G85996-004
J 0
(-6525 3600);
DISPLAY 0.617021 (-6525 3600);
PAINT BLUE (-6525 3600);
FORCEPROP 1 LAST WATTAGE 1/16W
J 2
(-6400 3550);
DISPLAY 0.617021 (-6400 3550);
PAINT SKYBLUE (-6400 3550);
FORCEPROP 1 LASTPIN (-6475 3500) $PN 1
J 0
(-6463 3512);
DISPLAY 0.787234 (-6463 3512);
PAINT ORANGE (-6463 3512);
FORCEPROP 1 LAST MATERIAL CHIP
J 0
(-6350 3550);
DISPLAY 0.617021 (-6350 3550);
PAINT SKYBLUE (-6350 3550);
FORCEPROP 1 LAST PACK_TYPE 0402
J 0
(-6300 3600);
DISPLAY 0.617021 (-6300 3600);
PAINT SKYBLUE (-6300 3600);
FORCEPROP 0 LAST FAIR_SS 064.9530D.M001
J 0
(-6425 3400);
DISPLAY 0.638298 (-6425 3400);
PAINT BROWN (-6425 3400);
DISPLAY BOTH (-6425 3400);
FORCEPROP 0 LAST GROUP POWER_FAIR
J 0
(-6500 3450);
DISPLAY 0.638298 (-6500 3450);
PAINT BROWN (-6500 3450);
DISPLAY BOTH (-6500 3450);
FORCEPROP 1 LASTPIN (-6275 3500) $PN 2
J 0
(-6313 3512);
DISPLAY 0.787234 (-6313 3512);
PAINT ORANGE (-6313 3512);
FORCEPROP 2 LAST SEC_TYPE 0402
J 0
(-6425 3700);
DISPLAY 1.021277 (-6425 3700);
PAINT ORANGE (-6425 3700);
DISPLAY INVISIBLE (-6425 3700);
FORCEPROP 0 LAST SEC 1
J 0
(-6300 3650);
DISPLAY 0.680851 (-6300 3650);
PAINT MONO (-6300 3650);
DISPLAY INVISIBLE (-6300 3650);
FORCEPROP 0 LAST ROOM SB
J 0
(-6325 3725);
DISPLAY 1.021277 (-6325 3725);
PAINT ORANGE (-6325 3725);
DISPLAY INVISIBLE (-6325 3725);
FORCEPROP 2 LAST CDS_LIB mstr_discrete
J 0
(-6375 3500);
PAINT MONO (-6375 3500);
DISPLAY INVISIBLE (-6375 3500);
FORCEPROP 1 LAST PATH I151
J 0
(-6425 3650);
DISPLAY 0.978723 (-6425 3650);
PAINT WHITE (-6425 3650);
DISPLAY INVISIBLE (-6425 3650);
FORCEADD RES..1
(-6000 3500);
FORCEPROP 1 LASTPIN (-6100 3500) $PN 1
J 0
(-6088 3512);
DISPLAY 0.787234 (-6088 3512);
PAINT ORANGE (-6088 3512);
FORCEPROP 1 LAST VALUE 1.0K
J 2
(-5975 3650);
DISPLAY 0.617021 (-5975 3650);
PAINT SKYBLUE (-5975 3650);
FORCEPROP 1 LAST LOCATION RF9
J 0
(-6150 3650);
DISPLAY 0.617021 (-6150 3650);
PAINT AQUA (-6150 3650);
FORCEPROP 1 LAST TOLERANCE 0.1%
J 0
(-5950 3650);
DISPLAY 0.617021 (-5950 3650);
PAINT SKYBLUE (-5950 3650);
FORCEPROP 1 LAST WATTAGE 1/16W
J 2
(-6000 3550);
DISPLAY 0.617021 (-6000 3550);
PAINT SKYBLUE (-6000 3550);
FORCEPROP 1 LAST PART_NUMBER G85996-004
J 0
(-6150 3600);
DISPLAY 0.617021 (-6150 3600);
PAINT BLUE (-6150 3600);
FORCEPROP 1 LAST PACK_TYPE 0402
J 0
(-5900 3600);
DISPLAY 0.617021 (-5900 3600);
PAINT SKYBLUE (-5900 3600);
FORCEPROP 0 LAST FAIR_SS 064.9530D.M001
J 0
(-5950 3400);
DISPLAY 0.638298 (-5950 3400);
PAINT BROWN (-5950 3400);
DISPLAY BOTH (-5950 3400);
FORCEPROP 0 LAST GROUP POWER_FAIR
J 0
(-6100 3450);
DISPLAY 0.638298 (-6100 3450);
PAINT BROWN (-6100 3450);
DISPLAY BOTH (-6100 3450);
FORCEPROP 1 LASTPIN (-5900 3500) $PN 2
J 0
(-5938 3512);
DISPLAY 0.787234 (-5938 3512);
PAINT ORANGE (-5938 3512);
FORCEPROP 1 LAST MATERIAL CHIP
J 0
(-5950 3550);
DISPLAY 0.617021 (-5950 3550);
PAINT SKYBLUE (-5950 3550);
FORCEPROP 0 LAST SEC 1
J 0
(-5900 3650);
DISPLAY 0.680851 (-5900 3650);
PAINT MONO (-5900 3650);
DISPLAY INVISIBLE (-5900 3650);
FORCEPROP 2 LAST SEC_TYPE 0402
J 0
(-5950 3700);
DISPLAY 1.021277 (-5950 3700);
PAINT ORANGE (-5950 3700);
DISPLAY INVISIBLE (-5950 3700);
FORCEPROP 2 LAST CDS_LIB mstr_discrete
J 0
(-6000 3500);
PAINT MONO (-6000 3500);
DISPLAY INVISIBLE (-6000 3500);
FORCEPROP 0 LAST ROOM SB
J 0
(-5950 3725);
DISPLAY 1.021277 (-5950 3725);
PAINT ORANGE (-5950 3725);
DISPLAY INVISIBLE (-5950 3725);
FORCEPROP 1 LAST PATH I152
J 0
(-6050 3650);
DISPLAY 0.978723 (-6050 3650);
PAINT WHITE (-6050 3650);
DISPLAY INVISIBLE (-6050 3650);
FORCEADD RES..1
(-5550 3500);
FORCEPROP 0 LAST FAIR_SS 064.9530D.M001
J 0
(-5450 3400);
DISPLAY 0.638298 (-5450 3400);
PAINT BROWN (-5450 3400);
DISPLAY BOTH (-5450 3400);
FORCEPROP 1 LASTPIN (-5450 3500) $PN 2
J 0
(-5488 3512);
DISPLAY 0.787234 (-5488 3512);
PAINT ORANGE (-5488 3512);
FORCEPROP 1 LAST PART_NUMBER G85996-004
J 0
(-5700 3600);
DISPLAY 0.617021 (-5700 3600);
PAINT BLUE (-5700 3600);
FORCEPROP 1 LAST WATTAGE 1/16W
J 2
(-5550 3550);
DISPLAY 0.617021 (-5550 3550);
PAINT SKYBLUE (-5550 3550);
FORCEPROP 1 LAST VALUE 1.0K
J 2
(-5525 3650);
DISPLAY 0.617021 (-5525 3650);
PAINT SKYBLUE (-5525 3650);
FORCEPROP 1 LAST MATERIAL CHIP
J 0
(-5500 3550);
DISPLAY 0.617021 (-5500 3550);
PAINT SKYBLUE (-5500 3550);
FORCEPROP 1 LAST TOLERANCE 0.1%
J 0
(-5500 3650);
DISPLAY 0.617021 (-5500 3650);
PAINT SKYBLUE (-5500 3650);
FORCEPROP 1 LAST PACK_TYPE 0402
J 0
(-5475 3600);
DISPLAY 0.617021 (-5475 3600);
PAINT SKYBLUE (-5475 3600);
FORCEPROP 1 LAST LOCATION RF10
J 0
(-5700 3650);
DISPLAY 0.617021 (-5700 3650);
PAINT AQUA (-5700 3650);
FORCEPROP 0 LAST GROUP POWER_FAIR
J 0
(-5700 3450);
DISPLAY 0.638298 (-5700 3450);
PAINT BROWN (-5700 3450);
DISPLAY BOTH (-5700 3450);
FORCEPROP 1 LASTPIN (-5650 3500) $PN 1
J 0
(-5638 3512);
DISPLAY 0.787234 (-5638 3512);
PAINT ORANGE (-5638 3512);
FORCEPROP 0 LAST SEC 1
J 0
(-5475 3650);
DISPLAY 0.680851 (-5475 3650);
PAINT MONO (-5475 3650);
DISPLAY INVISIBLE (-5475 3650);
FORCEPROP 2 LAST SEC_TYPE 0402
J 0
(-5500 3700);
DISPLAY 1.021277 (-5500 3700);
PAINT ORANGE (-5500 3700);
DISPLAY INVISIBLE (-5500 3700);
FORCEPROP 0 LAST ROOM SB
J 0
(-5500 3725);
DISPLAY 1.021277 (-5500 3725);
PAINT ORANGE (-5500 3725);
DISPLAY INVISIBLE (-5500 3725);
FORCEPROP 2 LAST CDS_LIB mstr_discrete
J 0
(-5550 3500);
PAINT MONO (-5550 3500);
DISPLAY INVISIBLE (-5550 3500);
FORCEPROP 1 LAST PATH I153
J 0
(-5600 3650);
DISPLAY 0.978723 (-5600 3650);
PAINT WHITE (-5600 3650);
DISPLAY INVISIBLE (-5600 3650);
FORCEADD RES..1
(-5100 3500);
FORCEPROP 0 LAST FAIR_SS 064.9530D.M001
J 0
(-4950 3400);
DISPLAY 0.638298 (-4950 3400);
PAINT BROWN (-4950 3400);
DISPLAY BOTH (-4950 3400);
FORCEPROP 1 LAST VALUE 1.0K
J 2
(-5075 3650);
DISPLAY 0.617021 (-5075 3650);
PAINT SKYBLUE (-5075 3650);
FORCEPROP 1 LAST LOCATION RF11
J 0
(-5250 3650);
DISPLAY 0.617021 (-5250 3650);
PAINT AQUA (-5250 3650);
FORCEPROP 1 LAST WATTAGE 1/16W
J 2
(-5100 3550);
DISPLAY 0.617021 (-5100 3550);
PAINT SKYBLUE (-5100 3550);
FORCEPROP 1 LAST PART_NUMBER G85996-004
J 0
(-5250 3600);
DISPLAY 0.617021 (-5250 3600);
PAINT BLUE (-5250 3600);
FORCEPROP 1 LASTPIN (-5200 3500) $PN 1
J 0
(-5188 3512);
DISPLAY 0.787234 (-5188 3512);
PAINT ORANGE (-5188 3512);
FORCEPROP 0 LAST GROUP POWER_FAIR
J 0
(-5250 3450);
DISPLAY 0.638298 (-5250 3450);
PAINT BROWN (-5250 3450);
DISPLAY BOTH (-5250 3450);
FORCEPROP 1 LASTPIN (-5000 3500) $PN 2
J 0
(-5038 3512);
DISPLAY 0.787234 (-5038 3512);
PAINT ORANGE (-5038 3512);
FORCEPROP 1 LAST MATERIAL CHIP
J 0
(-5050 3550);
DISPLAY 0.617021 (-5050 3550);
PAINT SKYBLUE (-5050 3550);
FORCEPROP 1 LAST PACK_TYPE 0402
J 0
(-5025 3600);
DISPLAY 0.617021 (-5025 3600);
PAINT SKYBLUE (-5025 3600);
FORCEPROP 1 LAST TOLERANCE 0.1%
J 0
(-5050 3650);
DISPLAY 0.617021 (-5050 3650);
PAINT SKYBLUE (-5050 3650);
FORCEPROP 1 LAST PATH I154
J 0
(-5150 3650);
DISPLAY 0.978723 (-5150 3650);
PAINT WHITE (-5150 3650);
DISPLAY INVISIBLE (-5150 3650);
FORCEPROP 2 LAST CDS_LIB mstr_discrete
J 0
(-5100 3500);
PAINT MONO (-5100 3500);
DISPLAY INVISIBLE (-5100 3500);
FORCEPROP 0 LAST ROOM SB
J 0
(-5050 3725);
DISPLAY 1.021277 (-5050 3725);
PAINT ORANGE (-5050 3725);
DISPLAY INVISIBLE (-5050 3725);
FORCEPROP 2 LAST SEC_TYPE 0402
J 0
(-5050 3700);
DISPLAY 1.021277 (-5050 3700);
PAINT ORANGE (-5050 3700);
DISPLAY INVISIBLE (-5050 3700);
FORCEPROP 0 LAST SEC 1
J 0
(-5025 3650);
DISPLAY 0.680851 (-5025 3650);
PAINT MONO (-5025 3650);
DISPLAY INVISIBLE (-5025 3650);
FORCEADD RES..2
(-2050 4150);
FORCEPROP 1 LASTPIN (-2050 4250) $PN 1
J 0
(-2045 4212);
DISPLAY 0.617021 (-2045 4212);
PAINT WHITE (-2045 4212);
FORCEPROP 1 LAST WATTAGE 1/16W
J 0
(-2010 4125);
DISPLAY 0.617021 (-2010 4125);
PAINT SKYBLUE (-2010 4125);
FORCEPROP 1 LAST VALUE 1.00K
J 0
(-2005 4225);
DISPLAY 0.617021 (-2005 4225);
PAINT SKYBLUE (-2005 4225);
FORCEPROP 1 LAST PACK_TYPE 0402
J 0
(-2010 3975);
DISPLAY 0.617021 (-2010 3975);
PAINT SKYBLUE (-2010 3975);
FORCEPROP 1 LAST MATERIAL CHIP
J 0
(-2010 4075);
DISPLAY 0.617021 (-2010 4075);
PAINT SKYBLUE (-2010 4075);
FORCEPROP 1 LAST TOLERANCE 1%
J 0
(-2005 4175);
DISPLAY 0.617021 (-2005 4175);
PAINT SKYBLUE (-2005 4175);
FORCEPROP 1 LASTPIN (-2050 4050) $PN 2
J 0
(-2045 4060);
DISPLAY 0.617021 (-2045 4060);
PAINT WHITE (-2045 4060);
FORCEPROP 1 LAST LOCATION R1D7
J 0
(-2005 4275);
DISPLAY 0.617021 (-2005 4275);
PAINT AQUA (-2005 4275);
FORCEPROP 1 LAST PART_NUMBER G21796-026
J 0
(-2010 4025);
DISPLAY 0.617021 (-2010 4025);
PAINT BLUE (-2010 4025);
FORCEPROP 2 LAST CDS_LOCATION R1D7
J 0
(-2005 4275);
DISPLAY 0.617021 (-2005 4275);
PAINT AQUA (-2005 4275);
DISPLAY INVISIBLE (-2005 4275);
FORCEPROP 2 LAST SEC_TYPE 0402
J 0
(-2000 4375);
DISPLAY 1.021277 (-2000 4375);
PAINT ORANGE (-2000 4375);
DISPLAY INVISIBLE (-2000 4375);
FORCEPROP 2 LAST SEC 1
J 0
(-2000 4375);
DISPLAY 0.680851 (-2000 4375);
PAINT MONO (-2000 4375);
DISPLAY INVISIBLE (-2000 4375);
FORCEPROP 2 LAST ROOM PVCCIN_CPU1_VR
J 0
(-2000 4325);
DISPLAY 1.361702 (-2000 4325);
PAINT WHITE (-2000 4325);
DISPLAY INVISIBLE (-2000 4325);
FORCEPROP 2 LAST CDS_LIB mstr_discrete
J 2
(-2050 4150);
PAINT ORANGE (-2050 4150);
DISPLAY INVISIBLE (-2050 4150);
FORCEPROP 1 LAST PATH I155
J 0
(-2000 4325);
DISPLAY 0.978723 (-2000 4325);
PAINT WHITE (-2000 4325);
DISPLAY INVISIBLE (-2000 4325);
FORCEADD CAP_A..1
(-6750 4200);
FORCEPROP 1 LASTPIN (-6750 4300) $PN 1
J 0
(-6740 4280);
DISPLAY 0.787234 (-6740 4280);
PAINT ORANGE (-6740 4280);
FORCEPROP 1 LAST MATERIAL X7R
J 0
(-6700 4150);
DISPLAY 0.617021 (-6700 4150);
PAINT SKYBLUE (-6700 4150);
FORCEPROP 1 LASTPIN (-6750 4100) $PN 2
J 0
(-6740 4080);
DISPLAY 0.787234 (-6740 4080);
PAINT ORANGE (-6740 4080);
FORCEPROP 1 LAST TOLERANCE 10%
J 0
(-6700 4200);
DISPLAY 0.617021 (-6700 4200);
PAINT SKYBLUE (-6700 4200);
FORCEPROP 1 LAST VOLTAGE 16V
J 0
(-6700 4250);
DISPLAY 0.617021 (-6700 4250);
PAINT SKYBLUE (-6700 4250);
FORCEPROP 1 LAST VALUE 0.1UF
J 0
(-6700 4300);
DISPLAY 0.617021 (-6700 4300);
PAINT SKYBLUE (-6700 4300);
FORCEPROP 1 LAST LOCATION C1C8
J 0
(-6700 4350);
DISPLAY 0.617021 (-6700 4350);
PAINT AQUA (-6700 4350);
FORCEPROP 1 LAST PACK_TYPE 0402V
J 0
(-6700 4050);
DISPLAY 0.617021 (-6700 4050);
PAINT SKYBLUE (-6700 4050);
FORCEPROP 1 LAST PART_NUMBER A36096-030
J 0
(-6700 4100);
DISPLAY 0.617021 (-6700 4100);
PAINT BLUE (-6700 4100);
FORCEPROP 2 LAST CDS_LIB dev_discrete
J 0
(-6750 4200);
PAINT MONO (-6750 4200);
DISPLAY INVISIBLE (-6750 4200);
FORCEPROP 0 LAST BOM_COST SM_THERM
J 0
(-6700 4350);
DISPLAY 1.021277 (-6700 4350);
PAINT ORANGE (-6700 4350);
DISPLAY INVISIBLE (-6700 4350);
FORCEPROP 0 LAST ROOM CPU_FANS
J 0
(-6700 4400);
DISPLAY 1.021277 (-6700 4400);
PAINT ORANGE (-6700 4400);
DISPLAY INVISIBLE (-6700 4400);
FORCEPROP 2 LAST SEC_TYPE 0402V
J 0
(-6700 4400);
DISPLAY 1.021277 (-6700 4400);
PAINT ORANGE (-6700 4400);
DISPLAY INVISIBLE (-6700 4400);
FORCEPROP 2 LAST SEC 1
J 0
(-6700 4400);
DISPLAY 0.680851 (-6700 4400);
PAINT MONO (-6700 4400);
DISPLAY INVISIBLE (-6700 4400);
FORCEPROP 0 LAST CDS_SEC 1
J 0
(-6700 4350);
PAINT MONO (-6700 4350);
DISPLAY INVISIBLE (-6700 4350);
FORCEPROP 1 LAST PATH I156
J 0
(-6700 4350);
DISPLAY 0.978723 (-6700 4350);
PAINT WHITE (-6700 4350);
DISPLAY INVISIBLE (-6700 4350);
FORCEPROP 0 LAST CDS_LOCATION C1C8
J 0
(-6700 4350);
PAINT MONO (-6700 4350);
DISPLAY INVISIBLE (-6700 4350);
FORCEADD OFFPAGE..2
(-1150 2375);
FORCEPROP 2 LAST $XR0 208 
J 0
(-961 2375);
DISPLAY 0.638298 (-961 2375);
PAINT MONO (-961 2375);
FORCEPROP 1 LAST COMMENT_BODY TRUE
J 0
(-1195 2280);
DISPLAY 1.170213 (-1195 2280);
PAINT PEACH (-1195 2280);
DISPLAY INVISIBLE (-1195 2280);
FORCEPROP 1 LAST OFFPAGE TRUE
J 0
(-825 2250);
DISPLAY 1.170213 (-825 2250);
PAINT GREEN (-825 2250);
DISPLAY INVISIBLE (-825 2250);
FORCEPROP 2 LAST PATH I16
J 0
(-950 2425);
DISPLAY 1.021277 (-950 2425);
PAINT ORANGE (-950 2425);
DISPLAY INVISIBLE (-950 2425);
FORCEPROP 2 LAST CDS_LIB mstr_standard
J 0
(-1150 2375);
PAINT ORANGE (-1150 2375);
DISPLAY INVISIBLE (-1150 2375);
FORCEPROP 2 LAST ROOM PVCCIN_CPU1_VR
J 0
(-1575 2450);
DISPLAY 1.361702 (-1575 2450);
PAINT WHITE (-1575 2450);
DISPLAY INVISIBLE (-1575 2450);
FORCEADD OFFPAGE..2
(-1150 2425);
FORCEPROP 2 LAST $XR0 208 
J 0
(-961 2425);
DISPLAY 0.638298 (-961 2425);
PAINT MONO (-961 2425);
FORCEPROP 1 LAST COMMENT_BODY TRUE
J 0
(-1195 2330);
DISPLAY 1.170213 (-1195 2330);
PAINT PEACH (-1195 2330);
DISPLAY INVISIBLE (-1195 2330);
FORCEPROP 1 LAST OFFPAGE TRUE
J 0
(-825 2300);
DISPLAY 1.170213 (-825 2300);
PAINT GREEN (-825 2300);
DISPLAY INVISIBLE (-825 2300);
FORCEPROP 2 LAST PATH I17
J 0
(-950 2475);
DISPLAY 1.021277 (-950 2475);
PAINT ORANGE (-950 2475);
DISPLAY INVISIBLE (-950 2475);
FORCEPROP 2 LAST CDS_LIB mstr_standard
J 0
(-1150 2425);
PAINT ORANGE (-1150 2425);
DISPLAY INVISIBLE (-1150 2425);
FORCEPROP 2 LAST ROOM PVCCIN_CPU1_VR
J 0
(-1575 2500);
DISPLAY 1.361702 (-1575 2500);
PAINT WHITE (-1575 2500);
DISPLAY INVISIBLE (-1575 2500);
FORCEADD OFFPAGE..2
(-1150 2325);
FORCEPROP 2 LAST $XR0 209 
J 0
(-961 2325);
DISPLAY 0.638298 (-961 2325);
PAINT MONO (-961 2325);
FORCEPROP 1 LAST COMMENT_BODY TRUE
J 0
(-1195 2230);
DISPLAY 1.170213 (-1195 2230);
PAINT PEACH (-1195 2230);
DISPLAY INVISIBLE (-1195 2230);
FORCEPROP 1 LAST OFFPAGE TRUE
J 0
(-825 2200);
DISPLAY 1.170213 (-825 2200);
PAINT GREEN (-825 2200);
DISPLAY INVISIBLE (-825 2200);
FORCEPROP 2 LAST PATH I18
J 0
(-975 2400);
DISPLAY 1.021277 (-975 2400);
PAINT ORANGE (-975 2400);
DISPLAY INVISIBLE (-975 2400);
FORCEPROP 2 LAST CDS_LIB mstr_standard
J 0
(-1150 2325);
PAINT ORANGE (-1150 2325);
DISPLAY INVISIBLE (-1150 2325);
FORCEPROP 2 LAST ROOM PVCCIN_CPU1_VR
J 0
(-1575 2400);
DISPLAY 1.361702 (-1575 2400);
PAINT WHITE (-1575 2400);
DISPLAY INVISIBLE (-1575 2400);
FORCEADD OFFPAGE..3
(-850 1775);
FORCEPROP 2 LAST $XR11 235 
J 0
(-276 1811);
DISPLAY 0.638298 (-276 1811);
PAINT MONO (-276 1811);
FORCEPROP 2 LAST $XR10 226 
J 0
(-396 1811);
DISPLAY 0.638298 (-396 1811);
PAINT MONO (-396 1811);
FORCEPROP 2 LAST $XR9 223 
J 0
(-516 1811);
DISPLAY 0.638298 (-516 1811);
PAINT MONO (-516 1811);
FORCEPROP 2 LAST $XR8 218 
J 0
(-636 1811);
DISPLAY 0.638298 (-636 1811);
PAINT MONO (-636 1811);
FORCEPROP 2 LAST $XR7 215 
J 0
(-276 1739);
DISPLAY 0.638298 (-276 1739);
PAINT MONO (-276 1739);
FORCEPROP 2 LAST $XR6 213 
J 0
(-396 1739);
DISPLAY 0.638298 (-396 1739);
PAINT MONO (-396 1739);
FORCEPROP 2 LAST $XR5 211 
J 0
(-516 1739);
DISPLAY 0.638298 (-516 1739);
PAINT MONO (-516 1739);
FORCEPROP 2 LAST $XR4 201 
J 0
(-636 1739);
DISPLAY 0.638298 (-636 1739);
PAINT MONO (-636 1739);
FORCEPROP 2 LAST $XR3 194 
J 0
(-276 1775);
DISPLAY 0.638298 (-276 1775);
PAINT MONO (-276 1775);
FORCEPROP 2 LAST $XR2 193 
J 0
(-396 1775);
DISPLAY 0.638298 (-396 1775);
PAINT MONO (-396 1775);
FORCEPROP 2 LAST $XR1 159 
J 0
(-516 1775);
DISPLAY 0.638298 (-516 1775);
PAINT MONO (-516 1775);
FORCEPROP 2 LAST $XR0 138 
J 0
(-636 1775);
DISPLAY 0.638298 (-636 1775);
PAINT MONO (-636 1775);
FORCEPROP 1 LAST COMMENT_BODY TRUE
J 0
(-900 1675);
DISPLAY 1.170213 (-900 1675);
PAINT PEACH (-900 1675);
DISPLAY INVISIBLE (-900 1675);
FORCEPROP 1 LAST OFFPAGE TRUE
J 0
(-525 1650);
DISPLAY 1.170213 (-525 1650);
PAINT GREEN (-525 1650);
DISPLAY INVISIBLE (-525 1650);
FORCEPROP 2 LAST PATH I23
J 0
(-275 1825);
DISPLAY 1.021277 (-275 1825);
PAINT ORANGE (-275 1825);
DISPLAY INVISIBLE (-275 1825);
FORCEPROP 2 LAST CDS_LIB mstr_standard
J 0
(-850 1775);
PAINT ORANGE (-850 1775);
DISPLAY INVISIBLE (-850 1775);
FORCEPROP 2 LAST ROOM PVCCIN_CPU1_VR
J 0
(-1250 1850);
DISPLAY 1.361702 (-1250 1850);
PAINT WHITE (-1250 1850);
DISPLAY INVISIBLE (-1250 1850);
FORCEADD OFFPAGE..1
R 2
(-850 1525);
FORCEPROP 2 LAST $XR11 226 
J 0
(-304 1561);
DISPLAY 0.638298 (-304 1561);
PAINT MONO (-304 1561);
FORCEPROP 2 LAST $XR10 223 
J 0
(-424 1561);
DISPLAY 0.638298 (-424 1561);
PAINT MONO (-424 1561);
FORCEPROP 2 LAST $XR9 218 
J 0
(-544 1561);
DISPLAY 0.638298 (-544 1561);
PAINT MONO (-544 1561);
FORCEPROP 2 LAST $XR8 215 
J 0
(-664 1561);
DISPLAY 0.638298 (-664 1561);
PAINT MONO (-664 1561);
FORCEPROP 2 LAST $XR7 201 
J 0
(-304 1489);
DISPLAY 0.638298 (-304 1489);
PAINT MONO (-304 1489);
FORCEPROP 2 LAST $XR6 194 
J 0
(-424 1489);
DISPLAY 0.638298 (-424 1489);
PAINT MONO (-424 1489);
FORCEPROP 2 LAST $XR5 193 
J 0
(-544 1489);
DISPLAY 0.638298 (-544 1489);
PAINT MONO (-544 1489);
FORCEPROP 2 LAST $XR4 235 
J 0
(-664 1489);
DISPLAY 0.638298 (-664 1489);
PAINT MONO (-664 1489);
FORCEPROP 2 LAST $XR3 213 
J 0
(-304 1525);
DISPLAY 0.638298 (-304 1525);
PAINT MONO (-304 1525);
FORCEPROP 2 LAST $XR2 211 
J 0
(-424 1525);
DISPLAY 0.638298 (-424 1525);
PAINT MONO (-424 1525);
FORCEPROP 2 LAST $XR1 159 
J 0
(-544 1525);
DISPLAY 0.638298 (-544 1525);
PAINT MONO (-544 1525);
FORCEPROP 2 LAST $XR0 138 
J 0
(-664 1525);
DISPLAY 0.638298 (-664 1525);
PAINT MONO (-664 1525);
FORCEPROP 1 LAST COMMENT_BODY TRUE
J 2
(-975 1425);
DISPLAY 1.170213 (-975 1425);
PAINT PEACH (-975 1425);
DISPLAY INVISIBLE (-975 1425);
FORCEPROP 1 LAST OFFPAGE TRUE
J 2
(-1175 1400);
DISPLAY 1.170213 (-1175 1400);
PAINT GREEN (-1175 1400);
DISPLAY INVISIBLE (-1175 1400);
FORCEPROP 2 LAST PATH I24
J 0
(-300 1575);
DISPLAY 1.021277 (-300 1575);
PAINT ORANGE (-300 1575);
DISPLAY INVISIBLE (-300 1575);
FORCEPROP 2 LAST CDS_LIB mstr_standard
J 0
(-850 1525);
PAINT ORANGE (-850 1525);
DISPLAY INVISIBLE (-850 1525);
FORCEPROP 2 LAST ROOM PVCCIN_CPU1_VR
J 0
(-1275 1600);
DISPLAY 1.361702 (-1275 1600);
PAINT WHITE (-1275 1600);
DISPLAY INVISIBLE (-1275 1600);
FORCEADD OFFPAGE..1
R 2
(-950 1175);
FORCEPROP 2 LAST $XR0 206 
J 0
(-764 1175);
DISPLAY 0.638298 (-764 1175);
PAINT MONO (-764 1175);
FORCEPROP 1 LAST COMMENT_BODY TRUE
J 2
(-1075 1075);
DISPLAY 1.170213 (-1075 1075);
PAINT PEACH (-1075 1075);
DISPLAY INVISIBLE (-1075 1075);
FORCEPROP 1 LAST OFFPAGE TRUE
J 2
(-1275 1050);
DISPLAY 1.170213 (-1275 1050);
PAINT GREEN (-1275 1050);
DISPLAY INVISIBLE (-1275 1050);
FORCEPROP 2 LAST PATH I26
J 0
(-750 1225);
DISPLAY 1.021277 (-750 1225);
PAINT ORANGE (-750 1225);
DISPLAY INVISIBLE (-750 1225);
FORCEPROP 2 LAST CDS_LIB mstr_standard
J 2
(-950 1175);
PAINT ORANGE (-950 1175);
DISPLAY INVISIBLE (-950 1175);
FORCEPROP 2 LAST ROOM PVCCIN_CPU1_VR
J 0
(-1375 1250);
DISPLAY 1.361702 (-1375 1250);
PAINT WHITE (-1375 1250);
DISPLAY INVISIBLE (-1375 1250);
FORCEADD CAP_A..1
(-1575 1000);
FORCEPROP 1 LAST PART_NUMBER D97712-004
J 0
(-1525 850);
DISPLAY 0.617021 (-1525 850);
PAINT BLUE (-1525 850);
FORCEPROP 1 LAST VOLTAGE 6.3V
J 0
(-1525 1000);
DISPLAY 0.617021 (-1525 1000);
PAINT SKYBLUE (-1525 1000);
FORCEPROP 1 LAST MATERIAL X6S
J 0
(-1525 900);
DISPLAY 0.617021 (-1525 900);
PAINT SKYBLUE (-1525 900);
FORCEPROP 1 LAST TOLERANCE 10%
J 0
(-1525 950);
DISPLAY 0.617021 (-1525 950);
PAINT SKYBLUE (-1525 950);
FORCEPROP 1 LAST PACK_TYPE 0402V
J 0
(-1525 800);
DISPLAY 0.617021 (-1525 800);
PAINT SKYBLUE (-1525 800);
FORCEPROP 1 LASTPIN (-1575 900) $PN 2
J 0
(-1565 880);
DISPLAY 0.787234 (-1565 880);
PAINT ORANGE (-1565 880);
FORCEPROP 1 LASTPIN (-1575 1100) $PN 1
J 0
(-1565 1080);
DISPLAY 0.787234 (-1565 1080);
PAINT ORANGE (-1565 1080);
FORCEPROP 1 LAST LOCATION C1C13
J 0
(-1525 1100);
DISPLAY 0.617021 (-1525 1100);
PAINT AQUA (-1525 1100);
FORCEPROP 1 LAST VALUE 1.0UF
J 0
(-1525 1050);
DISPLAY 0.617021 (-1525 1050);
PAINT SKYBLUE (-1525 1050);
FORCEPROP 2 LAST ROOM PVCCIN_CPU1_VR
J 0
(-1525 1150);
DISPLAY 1.361702 (-1525 1150);
PAINT WHITE (-1525 1150);
DISPLAY INVISIBLE (-1525 1150);
FORCEPROP 1 LAST PATH I29
J 0
(-1525 1150);
DISPLAY 0.978723 (-1525 1150);
PAINT WHITE (-1525 1150);
DISPLAY INVISIBLE (-1525 1150);
FORCEPROP 2 LAST CDS_LOCATION C1C13
J 0
(-1525 1100);
DISPLAY 0.617021 (-1525 1100);
PAINT AQUA (-1525 1100);
DISPLAY INVISIBLE (-1525 1100);
FORCEPROP 2 LAST CDS_LIB dev_discrete
J 0
(-1575 1000);
PAINT ORANGE (-1575 1000);
DISPLAY INVISIBLE (-1575 1000);
FORCEPROP 2 LAST SEC 1
J 0
(-1525 1200);
DISPLAY 0.680851 (-1525 1200);
PAINT MONO (-1525 1200);
DISPLAY INVISIBLE (-1525 1200);
FORCEPROP 2 LAST SEC_TYPE 0402V
J 0
(-1525 1200);
DISPLAY 1.021277 (-1525 1200);
PAINT ORANGE (-1525 1200);
DISPLAY INVISIBLE (-1525 1200);
FORCEADD GND..1
(-1575 675);
FORCEPROP 3 LASTPIN (-1575 725) SIG_NAME GND\g
J 0
(-1565 735);
DISPLAY 0.659574 (-1565 735);
PAINT MONO (-1565 735);
DISPLAY INVISIBLE (-1565 735);
FORCEPROP 1 LAST HDL_POWER GND
J 0
(-1575 825);
DISPLAY 1.170213 (-1575 825);
PAINT GREEN (-1575 825);
DISPLAY INVISIBLE (-1575 825);
FORCEPROP 1 LAST BODY_TYPE PLUMBING
J 0
(-1620 632);
DISPLAY 0.340426 (-1620 632);
PAINT GREEN (-1620 632);
DISPLAY INVISIBLE (-1620 632);
FORCEPROP 1 LAST SIZE 1B
J 0
(-1500 625);
DISPLAY 1.170213 (-1500 625);
PAINT AQUA (-1500 625);
DISPLAY INVISIBLE (-1500 625);
FORCEPROP 1 LAST PATH I30
J 0
(-1500 675);
DISPLAY 0.872340 (-1500 675);
PAINT AQUA (-1500 675);
DISPLAY INVISIBLE (-1500 675);
FORCEPROP 2 LAST CDS_LIB mstr_symbols
J 0
(-1575 675);
PAINT ORANGE (-1575 675);
DISPLAY INVISIBLE (-1575 675);
FORCEPROP 1 LAST VOLTAGE 0
J 0
(-1575 675);
PAINT SKYBLUE (-1575 675);
DISPLAY INVISIBLE (-1575 675);
FORCEPROP 2 LAST ROOM PVCCIN_CPU1_VR
J 0
(-2150 750);
DISPLAY 1.361702 (-2150 750);
PAINT WHITE (-2150 750);
DISPLAY INVISIBLE (-2150 750);
FORCEADD CAP_A..1
(-1975 1000);
FORCEPROP 1 LAST PACK_TYPE 0402V
J 0
(-1925 800);
DISPLAY 0.617021 (-1925 800);
PAINT SKYBLUE (-1925 800);
FORCEPROP 1 LAST MATERIAL X7R
J 0
(-1925 900);
DISPLAY 0.617021 (-1925 900);
PAINT SKYBLUE (-1925 900);
FORCEPROP 1 LAST PART_NUMBER A36096-030
J 0
(-1925 850);
DISPLAY 0.617021 (-1925 850);
PAINT BLUE (-1925 850);
FORCEPROP 1 LAST VALUE 0.1UF
J 0
(-1925 1050);
DISPLAY 0.617021 (-1925 1050);
PAINT SKYBLUE (-1925 1050);
FORCEPROP 1 LAST LOCATION C1C14
J 0
(-1925 1100);
DISPLAY 0.617021 (-1925 1100);
PAINT AQUA (-1925 1100);
FORCEPROP 1 LASTPIN (-1975 1100) $PN 1
J 0
(-1965 1080);
DISPLAY 0.617021 (-1965 1080);
PAINT WHITE (-1965 1080);
FORCEPROP 1 LAST VOLTAGE 16V
J 0
(-1925 1000);
DISPLAY 0.617021 (-1925 1000);
PAINT SKYBLUE (-1925 1000);
FORCEPROP 1 LAST TOLERANCE 10%
J 0
(-1925 950);
DISPLAY 0.617021 (-1925 950);
PAINT SKYBLUE (-1925 950);
FORCEPROP 1 LASTPIN (-1975 900) $PN 2
J 0
(-1965 880);
DISPLAY 0.617021 (-1965 880);
PAINT WHITE (-1965 880);
FORCEPROP 1 LAST PATH I31
J 0
(-1925 1150);
DISPLAY 0.978723 (-1925 1150);
PAINT WHITE (-1925 1150);
DISPLAY INVISIBLE (-1925 1150);
FORCEPROP 2 LAST ROOM PVCCIN_CPU1_VR
J 0
(-1925 1150);
DISPLAY 1.361702 (-1925 1150);
PAINT WHITE (-1925 1150);
DISPLAY INVISIBLE (-1925 1150);
FORCEPROP 2 LAST CDS_LOCATION C1C14
J 0
(-1925 1100);
DISPLAY 0.617021 (-1925 1100);
PAINT AQUA (-1925 1100);
DISPLAY INVISIBLE (-1925 1100);
FORCEPROP 2 LAST CDS_SEC 1
J 0
(-1925 1150);
PAINT ORANGE (-1925 1150);
DISPLAY INVISIBLE (-1925 1150);
FORCEPROP 2 LAST SEC_TYPE 0402V
J 0
(-1925 1200);
DISPLAY 1.021277 (-1925 1200);
PAINT ORANGE (-1925 1200);
DISPLAY INVISIBLE (-1925 1200);
FORCEPROP 2 LAST SEC 1
J 0
(-1925 1200);
DISPLAY 0.680851 (-1925 1200);
PAINT MONO (-1925 1200);
DISPLAY INVISIBLE (-1925 1200);
FORCEPROP 2 LAST CDS_LIB dev_discrete
J 0
(-1975 1000);
PAINT ORANGE (-1975 1000);
DISPLAY INVISIBLE (-1975 1000);
FORCEADD GND..1
(-1975 800);
FORCEPROP 3 LASTPIN (-1975 850) SIG_NAME GND\g
J 0
(-1965 860);
DISPLAY 0.659574 (-1965 860);
PAINT MONO (-1965 860);
DISPLAY INVISIBLE (-1965 860);
FORCEPROP 1 LAST HDL_POWER GND
J 0
(-1975 950);
DISPLAY 1.170213 (-1975 950);
PAINT GREEN (-1975 950);
DISPLAY INVISIBLE (-1975 950);
FORCEPROP 1 LAST BODY_TYPE PLUMBING
J 0
(-2020 757);
DISPLAY 0.340426 (-2020 757);
PAINT GREEN (-2020 757);
DISPLAY INVISIBLE (-2020 757);
FORCEPROP 1 LAST PATH I32
J 0
(-1900 800);
DISPLAY 0.872340 (-1900 800);
PAINT AQUA (-1900 800);
DISPLAY INVISIBLE (-1900 800);
FORCEPROP 2 LAST CDS_LIB mstr_symbols
J 0
(-1975 800);
PAINT ORANGE (-1975 800);
DISPLAY INVISIBLE (-1975 800);
FORCEPROP 1 LAST VOLTAGE 0
J 0
(-1975 800);
PAINT SKYBLUE (-1975 800);
DISPLAY INVISIBLE (-1975 800);
FORCEPROP 1 LAST SIZE 1B
J 0
(-1900 750);
DISPLAY 1.170213 (-1900 750);
PAINT AQUA (-1900 750);
DISPLAY INVISIBLE (-1900 750);
FORCEPROP 2 LAST ROOM PVCCIN_CPU1_VR
J 0
(-2550 875);
DISPLAY 1.361702 (-2550 875);
PAINT WHITE (-2550 875);
DISPLAY INVISIBLE (-2550 875);
FORCEADD RES..2
(-2375 4125);
FORCEPROP 1 LAST LOCATION R1D53
J 0
(-2330 4250);
DISPLAY 0.617021 (-2330 4250);
PAINT AQUA (-2330 4250);
FORCEPROP 1 LAST PART_NUMBER G21796-311
J 0
(-2335 4000);
DISPLAY 0.617021 (-2335 4000);
PAINT BLUE (-2335 4000);
FORCEPROP 1 LAST VALUE 2.26K
J 0
(-2330 4200);
DISPLAY 0.617021 (-2330 4200);
PAINT SKYBLUE (-2330 4200);
FORCEPROP 1 LAST PACK_TYPE 0402
J 0
(-2335 3950);
DISPLAY 0.617021 (-2335 3950);
PAINT SKYBLUE (-2335 3950);
FORCEPROP 1 LAST WATTAGE 1/16W
J 0
(-2335 4100);
DISPLAY 0.617021 (-2335 4100);
PAINT SKYBLUE (-2335 4100);
FORCEPROP 1 LAST TOLERANCE 1.0%
J 0
(-2330 4150);
DISPLAY 0.617021 (-2330 4150);
PAINT SKYBLUE (-2330 4150);
FORCEPROP 1 LASTPIN (-2375 4225) $PN 1
J 0
(-2370 4187);
DISPLAY 0.617021 (-2370 4187);
PAINT WHITE (-2370 4187);
FORCEPROP 1 LAST MATERIAL EMPTY
J 0
(-2535 4225);
DISPLAY 0.617021 (-2535 4225);
PAINT RED (-2535 4225);
FORCEPROP 1 LASTPIN (-2375 4025) $PN 2
J 0
(-2370 4035);
DISPLAY 0.617021 (-2370 4035);
PAINT WHITE (-2370 4035);
FORCEPROP 2 LAST SEC_TYPE 0402
J 0
(-2325 4350);
DISPLAY 1.021277 (-2325 4350);
PAINT ORANGE (-2325 4350);
DISPLAY INVISIBLE (-2325 4350);
FORCEPROP 2 LAST SEC 1
J 0
(-2325 4350);
DISPLAY 0.680851 (-2325 4350);
PAINT MONO (-2325 4350);
DISPLAY INVISIBLE (-2325 4350);
FORCEPROP 1 LAST PATH I33
J 0
(-2325 4300);
DISPLAY 0.978723 (-2325 4300);
PAINT WHITE (-2325 4300);
DISPLAY INVISIBLE (-2325 4300);
FORCEPROP 2 LAST CDS_LIB mstr_discrete
J 0
(-2375 4125);
PAINT ORANGE (-2375 4125);
DISPLAY INVISIBLE (-2375 4125);
FORCEPROP 2 LAST ROOM PVCCIN_CPU1_VR
J 0
(-2525 4275);
DISPLAY 1.361702 (-2525 4275);
PAINT WHITE (-2525 4275);
DISPLAY INVISIBLE (-2525 4275);
FORCEADD RES..2
(-2225 3750);
FORCEPROP 1 LAST TOLERANCE 1.0%
J 0
(-2180 3775);
DISPLAY 0.617021 (-2180 3775);
PAINT SKYBLUE (-2180 3775);
FORCEPROP 1 LAST VALUE 2.26K
J 0
(-2180 3825);
DISPLAY 0.617021 (-2180 3825);
PAINT SKYBLUE (-2180 3825);
FORCEPROP 1 LAST LOCATION R1C18
J 0
(-2180 3875);
DISPLAY 0.617021 (-2180 3875);
PAINT AQUA (-2180 3875);
FORCEPROP 1 LASTPIN (-2225 3650) $PN 2
J 0
(-2220 3660);
DISPLAY 0.617021 (-2220 3660);
PAINT WHITE (-2220 3660);
FORCEPROP 1 LASTPIN (-2225 3850) $PN 1
J 0
(-2220 3812);
DISPLAY 0.617021 (-2220 3812);
PAINT WHITE (-2220 3812);
FORCEPROP 1 LAST WATTAGE 1/16W
J 0
(-2185 3725);
DISPLAY 0.617021 (-2185 3725);
PAINT SKYBLUE (-2185 3725);
FORCEPROP 1 LAST MATERIAL EMPTY
J 0
(-2185 3675);
DISPLAY 0.617021 (-2185 3675);
PAINT RED (-2185 3675);
FORCEPROP 1 LAST PART_NUMBER G21796-311
J 0
(-2185 3625);
DISPLAY 0.617021 (-2185 3625);
PAINT BLUE (-2185 3625);
FORCEPROP 1 LAST PACK_TYPE 0402
J 0
(-2185 3575);
DISPLAY 0.617021 (-2185 3575);
PAINT SKYBLUE (-2185 3575);
FORCEPROP 2 LAST SEC_TYPE 0402
J 0
(-2175 3975);
DISPLAY 1.021277 (-2175 3975);
PAINT ORANGE (-2175 3975);
DISPLAY INVISIBLE (-2175 3975);
FORCEPROP 2 LAST SEC 1
J 0
(-2175 3975);
DISPLAY 0.680851 (-2175 3975);
PAINT MONO (-2175 3975);
DISPLAY INVISIBLE (-2175 3975);
FORCEPROP 2 LAST CDS_LOCATION R1C18
J 0
(-2180 3875);
DISPLAY 0.617021 (-2180 3875);
PAINT AQUA (-2180 3875);
DISPLAY INVISIBLE (-2180 3875);
FORCEPROP 1 LAST PATH I34
J 0
(-2175 3925);
DISPLAY 0.978723 (-2175 3925);
PAINT WHITE (-2175 3925);
DISPLAY INVISIBLE (-2175 3925);
FORCEPROP 2 LAST ROOM PVCCIN_CPU1_VR
J 0
(-2175 3725);
DISPLAY 1.361702 (-2175 3725);
PAINT WHITE (-2175 3725);
DISPLAY INVISIBLE (-2175 3725);
FORCEPROP 2 LAST CDS_LIB mstr_discrete
J 0
(-2225 3750);
PAINT ORANGE (-2225 3750);
DISPLAY INVISIBLE (-2225 3750);
FORCEADD RES..2
(-2725 3925);
FORCEPROP 1 LAST PART_NUMBER G21796-026
J 0
(-2685 3800);
DISPLAY 0.617021 (-2685 3800);
PAINT BLUE (-2685 3800);
FORCEPROP 1 LASTPIN (-2725 3825) $PN 2
J 0
(-2720 3835);
DISPLAY 0.617021 (-2720 3835);
PAINT WHITE (-2720 3835);
FORCEPROP 1 LAST MATERIAL CHIP
J 0
(-2685 3850);
DISPLAY 0.617021 (-2685 3850);
PAINT SKYBLUE (-2685 3850);
FORCEPROP 1 LAST WATTAGE 1/16W
J 0
(-2685 3900);
DISPLAY 0.617021 (-2685 3900);
PAINT SKYBLUE (-2685 3900);
FORCEPROP 1 LAST PACK_TYPE 0402
J 0
(-2685 3750);
DISPLAY 0.617021 (-2685 3750);
PAINT SKYBLUE (-2685 3750);
FORCEPROP 1 LAST TOLERANCE 1%
J 0
(-2680 3950);
DISPLAY 0.617021 (-2680 3950);
PAINT SKYBLUE (-2680 3950);
FORCEPROP 1 LASTPIN (-2725 4025) $PN 1
J 0
(-2720 3987);
DISPLAY 0.617021 (-2720 3987);
PAINT WHITE (-2720 3987);
FORCEPROP 1 LAST VALUE 1.00K
J 0
(-2680 4000);
DISPLAY 0.617021 (-2680 4000);
PAINT SKYBLUE (-2680 4000);
FORCEPROP 1 LAST LOCATION R1C28
J 0
(-2680 4050);
DISPLAY 0.617021 (-2680 4050);
PAINT AQUA (-2680 4050);
FORCEPROP 2 LAST CDS_LIB mstr_discrete
J 2
(-2725 3925);
PAINT ORANGE (-2725 3925);
DISPLAY INVISIBLE (-2725 3925);
FORCEPROP 2 LAST CDS_LOCATION R1C28
J 0
(-2680 4050);
DISPLAY 0.617021 (-2680 4050);
PAINT AQUA (-2680 4050);
DISPLAY INVISIBLE (-2680 4050);
FORCEPROP 2 LAST ROOM PVCCIN_CPU1_VR
J 0
(-2675 4100);
DISPLAY 1.361702 (-2675 4100);
PAINT WHITE (-2675 4100);
DISPLAY INVISIBLE (-2675 4100);
FORCEPROP 2 LAST SEC 1
J 0
(-2675 4150);
DISPLAY 0.680851 (-2675 4150);
PAINT MONO (-2675 4150);
DISPLAY INVISIBLE (-2675 4150);
FORCEPROP 2 LAST SEC_TYPE 0402
J 0
(-2675 4150);
DISPLAY 1.021277 (-2675 4150);
PAINT ORANGE (-2675 4150);
DISPLAY INVISIBLE (-2675 4150);
FORCEPROP 1 LAST PATH I35
J 0
(-2675 4100);
DISPLAY 0.978723 (-2675 4100);
PAINT WHITE (-2675 4100);
DISPLAY INVISIBLE (-2675 4100);
FORCEADD RES..2
R 2
(-2875 3925);
FORCEPROP 1 LASTPIN (-2875 4025) $PN 1
J 2
(-2880 3987);
DISPLAY 0.617021 (-2880 3987);
PAINT WHITE (-2880 3987);
FORCEPROP 1 LAST MATERIAL CHIP
J 2
(-2915 3850);
DISPLAY 0.617021 (-2915 3850);
PAINT SKYBLUE (-2915 3850);
FORCEPROP 1 LAST TOLERANCE 1%
J 2
(-2920 3950);
DISPLAY 0.617021 (-2920 3950);
PAINT SKYBLUE (-2920 3950);
FORCEPROP 1 LAST VALUE 1.00K
J 2
(-2920 4000);
DISPLAY 0.617021 (-2920 4000);
PAINT SKYBLUE (-2920 4000);
FORCEPROP 1 LAST LOCATION R1D8
J 2
(-2920 4050);
DISPLAY 0.617021 (-2920 4050);
PAINT AQUA (-2920 4050);
FORCEPROP 1 LAST WATTAGE 1/16W
J 2
(-2915 3900);
DISPLAY 0.617021 (-2915 3900);
PAINT SKYBLUE (-2915 3900);
FORCEPROP 1 LASTPIN (-2875 3825) $PN 2
J 2
(-2880 3835);
DISPLAY 0.617021 (-2880 3835);
PAINT WHITE (-2880 3835);
FORCEPROP 1 LAST PART_NUMBER G21796-026
J 2
(-2915 3800);
DISPLAY 0.617021 (-2915 3800);
PAINT BLUE (-2915 3800);
FORCEPROP 1 LAST PACK_TYPE 0402
J 2
(-2915 3750);
DISPLAY 0.617021 (-2915 3750);
PAINT SKYBLUE (-2915 3750);
FORCEPROP 2 LAST SEC_TYPE 0402
J 0
(-2925 4150);
DISPLAY 1.021277 (-2925 4150);
PAINT ORANGE (-2925 4150);
DISPLAY INVISIBLE (-2925 4150);
FORCEPROP 2 LAST SEC 1
J 0
(-2925 4150);
DISPLAY 0.680851 (-2925 4150);
PAINT MONO (-2925 4150);
DISPLAY INVISIBLE (-2925 4150);
FORCEPROP 1 LAST PATH I36
J 2
(-2925 4100);
DISPLAY 0.978723 (-2925 4100);
PAINT WHITE (-2925 4100);
DISPLAY INVISIBLE (-2925 4100);
FORCEPROP 2 LAST ROOM PVCCIN_CPU1_VR
J 0
(-2900 4100);
DISPLAY 1.361702 (-2900 4100);
PAINT WHITE (-2900 4100);
DISPLAY INVISIBLE (-2900 4100);
FORCEPROP 2 LAST CDS_LIB mstr_discrete
J 2
(-2875 3925);
PAINT ORANGE (-2875 3925);
DISPLAY INVISIBLE (-2875 3925);
FORCEPROP 2 LAST CDS_LOCATION R1D8
J 2
(-2920 4050);
DISPLAY 0.617021 (-2920 4050);
PAINT AQUA (-2920 4050);
DISPLAY INVISIBLE (-2920 4050);
FORCEADD RES..1
(-2125 2925);
FORCEPROP 1 LAST LOCATION R1D3
J 0
(-2175 2975);
DISPLAY 0.617021 (-2175 2975);
PAINT AQUA (-2175 2975);
FORCEPROP 1 LASTPIN (-2225 2925) $PN 1
J 0
(-2213 2937);
DISPLAY 0.617021 (-2213 2937);
PAINT WHITE (-2213 2937);
FORCEPROP 1 LAST WATTAGE 1/16W
J 2
(-1900 2975);
DISPLAY 0.617021 (-1900 2975);
PAINT SKYBLUE (-1900 2975);
FORCEPROP 1 LASTPIN (-2025 2925) $PN 2
J 0
(-2063 2937);
DISPLAY 0.617021 (-2063 2937);
PAINT WHITE (-2063 2937);
FORCEPROP 1 LAST MATERIAL CHIP
J 0
(-2100 2825);
DISPLAY 0.617021 (-2100 2825);
PAINT SKYBLUE (-2100 2825);
FORCEPROP 1 LAST VALUE 0.0
J 2
(-2175 2825);
DISPLAY 0.617021 (-2175 2825);
PAINT SKYBLUE (-2175 2825);
FORCEPROP 1 LAST TOLERANCE 5%
J 0
(-2200 2875);
DISPLAY 0.617021 (-2200 2875);
PAINT SKYBLUE (-2200 2875);
FORCEPROP 1 LAST PACK_TYPE 0402
J 0
(-2025 2875);
DISPLAY 0.617021 (-2025 2875);
PAINT SKYBLUE (-2025 2875);
FORCEPROP 1 LAST PART_NUMBER G21497-005
J 0
(-1875 2875);
DISPLAY 0.617021 (-1875 2875);
PAINT BLUE (-1875 2875);
FORCEPROP 1 LAST PATH I37
J 0
(-2175 3075);
DISPLAY 0.978723 (-2175 3075);
PAINT WHITE (-2175 3075);
DISPLAY INVISIBLE (-2175 3075);
FORCEPROP 2 LAST SEC 1
J 0
(-2175 3125);
DISPLAY 0.680851 (-2175 3125);
PAINT MONO (-2175 3125);
DISPLAY INVISIBLE (-2175 3125);
FORCEPROP 2 LAST SEC_TYPE 0402
J 0
(-2175 3125);
DISPLAY 1.021277 (-2175 3125);
PAINT ORANGE (-2175 3125);
DISPLAY INVISIBLE (-2175 3125);
FORCEPROP 2 LAST ROOM PVCCIN_CPU1_VR
J 0
(-2175 3025);
DISPLAY 1.361702 (-2175 3025);
PAINT WHITE (-2175 3025);
DISPLAY INVISIBLE (-2175 3025);
FORCEPROP 2 LAST CDS_LOCATION R1D3
J 0
(-2175 2975);
DISPLAY 0.617021 (-2175 2975);
PAINT AQUA (-2175 2975);
DISPLAY INVISIBLE (-2175 2975);
FORCEPROP 2 LAST CDS_LIB mstr_discrete
J 0
(-2125 2925);
PAINT ORANGE (-2125 2925);
DISPLAY INVISIBLE (-2125 2925);
FORCEADD RES..1
(-2500 2775);
FORCEPROP 1 LAST MATERIAL CHIP
J 0
(-2475 2575);
DISPLAY 0.617021 (-2475 2575);
PAINT SKYBLUE (-2475 2575);
FORCEPROP 1 LASTPIN (-2600 2775) $PN 1
J 0
(-2588 2787);
DISPLAY 0.617021 (-2588 2787);
PAINT WHITE (-2588 2787);
FORCEPROP 1 LAST LOCATION R1D2
J 0
(-2650 2725);
DISPLAY 0.617021 (-2650 2725);
PAINT AQUA (-2650 2725);
FORCEPROP 1 LAST PACK_TYPE 0402
J 0
(-2475 2625);
DISPLAY 0.617021 (-2475 2625);
PAINT SKYBLUE (-2475 2625);
FORCEPROP 1 LAST TOLERANCE 5%
J 0
(-2575 2625);
DISPLAY 0.617021 (-2575 2625);
PAINT SKYBLUE (-2575 2625);
FORCEPROP 1 LAST WATTAGE 1/16W
J 2
(-2525 2575);
DISPLAY 0.617021 (-2525 2575);
PAINT SKYBLUE (-2525 2575);
FORCEPROP 1 LAST VALUE 0.0
J 2
(-2625 2625);
DISPLAY 0.617021 (-2625 2625);
PAINT SKYBLUE (-2625 2625);
FORCEPROP 1 LAST PART_NUMBER G21497-005
J 0
(-2650 2675);
DISPLAY 0.617021 (-2650 2675);
PAINT BLUE (-2650 2675);
FORCEPROP 1 LASTPIN (-2400 2775) $PN 2
J 0
(-2438 2787);
DISPLAY 0.617021 (-2438 2787);
PAINT WHITE (-2438 2787);
FORCEPROP 2 LAST ROOM PVCCIN_CPU1_VR
J 0
(-2550 2875);
DISPLAY 1.361702 (-2550 2875);
PAINT WHITE (-2550 2875);
DISPLAY INVISIBLE (-2550 2875);
FORCEPROP 1 LAST PATH I38
J 0
(-2550 2925);
DISPLAY 0.978723 (-2550 2925);
PAINT WHITE (-2550 2925);
DISPLAY INVISIBLE (-2550 2925);
FORCEPROP 2 LAST CDS_LOCATION R1D2
J 0
(-2550 2825);
DISPLAY 0.617021 (-2550 2825);
PAINT AQUA (-2550 2825);
DISPLAY INVISIBLE (-2550 2825);
FORCEPROP 2 LAST SEC 1
J 0
(-2550 2975);
DISPLAY 0.680851 (-2550 2975);
PAINT MONO (-2550 2975);
DISPLAY INVISIBLE (-2550 2975);
FORCEPROP 2 LAST SEC_TYPE 0402
J 0
(-2550 2975);
DISPLAY 1.021277 (-2550 2975);
PAINT ORANGE (-2550 2975);
DISPLAY INVISIBLE (-2550 2975);
FORCEPROP 2 LAST CDS_LIB mstr_discrete
J 0
(-2500 2775);
PAINT ORANGE (-2500 2775);
DISPLAY INVISIBLE (-2500 2775);
FORCEADD RES..2
(-1375 3750);
FORCEPROP 1 LAST WATTAGE 1/16W
J 0
(-1335 3725);
DISPLAY 0.617021 (-1335 3725);
PAINT SKYBLUE (-1335 3725);
FORCEPROP 1 LAST TOLERANCE 1%
J 0
(-1330 3775);
DISPLAY 0.617021 (-1330 3775);
PAINT SKYBLUE (-1330 3775);
FORCEPROP 1 LAST LOCATION R9P1
J 0
(-1330 3875);
DISPLAY 0.617021 (-1330 3875);
PAINT AQUA (-1330 3875);
FORCEPROP 1 LASTPIN (-1375 3850) $PN 1
J 0
(-1370 3812);
DISPLAY 0.617021 (-1370 3812);
PAINT WHITE (-1370 3812);
FORCEPROP 1 LASTPIN (-1375 3650) $PN 2
J 0
(-1370 3660);
DISPLAY 0.617021 (-1370 3660);
PAINT WHITE (-1370 3660);
FORCEPROP 1 LAST PACK_TYPE 0402
J 0
(-1335 3575);
DISPLAY 0.617021 (-1335 3575);
PAINT SKYBLUE (-1335 3575);
FORCEPROP 1 LAST PART_NUMBER G21796-017
J 0
(-1335 3625);
DISPLAY 0.617021 (-1335 3625);
PAINT BLUE (-1335 3625);
FORCEPROP 1 LAST MATERIAL CHIP
J 0
(-1335 3675);
DISPLAY 0.617021 (-1335 3675);
PAINT SKYBLUE (-1335 3675);
FORCEPROP 1 LAST VALUE 100.0
J 0
(-1330 3825);
DISPLAY 0.617021 (-1330 3825);
PAINT SKYBLUE (-1330 3825);
FORCEPROP 2 LAST SEC_TYPE 0402
J 0
(-1325 3975);
DISPLAY 1.021277 (-1325 3975);
PAINT ORANGE (-1325 3975);
DISPLAY INVISIBLE (-1325 3975);
FORCEPROP 2 LAST SEC 1
J 0
(-1325 3975);
DISPLAY 0.680851 (-1325 3975);
PAINT MONO (-1325 3975);
DISPLAY INVISIBLE (-1325 3975);
FORCEPROP 2 LAST CDS_LOCATION R9P1
J 0
(-1330 3875);
DISPLAY 0.617021 (-1330 3875);
PAINT AQUA (-1330 3875);
DISPLAY INVISIBLE (-1330 3875);
FORCEPROP 1 LAST PATH I4
J 0
(-1325 3925);
DISPLAY 0.978723 (-1325 3925);
PAINT WHITE (-1325 3925);
DISPLAY INVISIBLE (-1325 3925);
FORCEPROP 2 LAST ROOM PVCCIN_CPU1_VR
J 0
(-1325 3925);
DISPLAY 1.361702 (-1325 3925);
PAINT WHITE (-1325 3925);
DISPLAY INVISIBLE (-1325 3925);
FORCEPROP 2 LAST CDS_LIB mstr_discrete
J 0
(-1375 3750);
PAINT ORANGE (-1375 3750);
DISPLAY INVISIBLE (-1375 3750);
FORCEADD GND..1
(-3650 3725);
FORCEPROP 3 LASTPIN (-3650 3775) SIG_NAME GND\g
J 0
(-3640 3785);
DISPLAY 0.659574 (-3640 3785);
PAINT MONO (-3640 3785);
DISPLAY INVISIBLE (-3640 3785);
FORCEPROP 1 LAST HDL_POWER GND
J 0
(-3650 3875);
DISPLAY 1.170213 (-3650 3875);
PAINT GREEN (-3650 3875);
DISPLAY INVISIBLE (-3650 3875);
FORCEPROP 1 LAST BODY_TYPE PLUMBING
J 0
(-3695 3682);
DISPLAY 0.340426 (-3695 3682);
PAINT GREEN (-3695 3682);
DISPLAY INVISIBLE (-3695 3682);
FORCEPROP 1 LAST SIZE 1B
J 0
(-3575 3675);
DISPLAY 1.170213 (-3575 3675);
PAINT AQUA (-3575 3675);
DISPLAY INVISIBLE (-3575 3675);
FORCEPROP 1 LAST PATH I40
J 0
(-3575 3725);
DISPLAY 0.872340 (-3575 3725);
PAINT AQUA (-3575 3725);
DISPLAY INVISIBLE (-3575 3725);
FORCEPROP 1 LAST VOLTAGE 0
J 0
(-3650 3725);
PAINT SKYBLUE (-3650 3725);
DISPLAY INVISIBLE (-3650 3725);
FORCEPROP 2 LAST CDS_LIB mstr_symbols
J 0
(-3650 3725);
PAINT ORANGE (-3650 3725);
DISPLAY INVISIBLE (-3650 3725);
FORCEPROP 2 LAST ROOM PVCCIN_CPU1_VR
J 0
(-4225 3800);
DISPLAY 1.361702 (-4225 3800);
PAINT WHITE (-4225 3800);
DISPLAY INVISIBLE (-4225 3800);
FORCEADD CAP_A..1
(-3650 3925);
FORCEPROP 1 LAST LOCATION C1C7
J 0
(-3600 4025);
DISPLAY 0.617021 (-3600 4025);
PAINT AQUA (-3600 4025);
FORCEPROP 1 LAST PART_NUMBER D97712-004
J 0
(-3600 3775);
DISPLAY 0.617021 (-3600 3775);
PAINT BLUE (-3600 3775);
FORCEPROP 1 LAST VALUE 1.0UF
J 0
(-3600 3975);
DISPLAY 0.617021 (-3600 3975);
PAINT SKYBLUE (-3600 3975);
FORCEPROP 1 LAST TOLERANCE 10%
J 0
(-3600 3875);
DISPLAY 0.617021 (-3600 3875);
PAINT SKYBLUE (-3600 3875);
FORCEPROP 1 LAST PACK_TYPE 0402V
J 0
(-3600 3725);
DISPLAY 0.617021 (-3600 3725);
PAINT SKYBLUE (-3600 3725);
FORCEPROP 1 LAST VOLTAGE 6.3V
J 0
(-3600 3925);
DISPLAY 0.617021 (-3600 3925);
PAINT SKYBLUE (-3600 3925);
FORCEPROP 1 LAST MATERIAL X6S
J 0
(-3600 3825);
DISPLAY 0.617021 (-3600 3825);
PAINT SKYBLUE (-3600 3825);
FORCEPROP 2 LAST CDS_SEC 1
J 0
(-3600 4125);
DISPLAY 1.021277 (-3600 4125);
PAINT ORANGE (-3600 4125);
DISPLAY INVISIBLE (-3600 4125);
FORCEPROP 2 LAST $SEC 1
J 0
(-3600 4125);
DISPLAY 0.680851 (-3600 4125);
PAINT MONO (-3600 4125);
DISPLAY INVISIBLE (-3600 4125);
FORCEPROP 1 LAST PATH I41
J 0
(-3600 4075);
DISPLAY 0.978723 (-3600 4075);
PAINT WHITE (-3600 4075);
DISPLAY INVISIBLE (-3600 4075);
FORCEPROP 2 LAST ROOM PVCCIN_CPU1_VR
J 0
(-3600 4075);
DISPLAY 1.361702 (-3600 4075);
PAINT WHITE (-3600 4075);
DISPLAY INVISIBLE (-3600 4075);
FORCEPROP 1 LASTPIN (-3650 4025) $PN 1
J 0
(-3640 4005);
DISPLAY 0.787234 (-3640 4005);
PAINT ORANGE (-3640 4005);
DISPLAY INVISIBLE (-3640 4005);
FORCEPROP 2 LAST CDS_LOCATION C1C7
J 0
(-3600 4025);
DISPLAY 0.617021 (-3600 4025);
PAINT AQUA (-3600 4025);
DISPLAY INVISIBLE (-3600 4025);
FORCEPROP 2 LAST CDS_LIB dev_discrete
J 0
(-3650 3925);
PAINT ORANGE (-3650 3925);
DISPLAY INVISIBLE (-3650 3925);
FORCEPROP 1 LASTPIN (-3650 3825) $PN 2
J 0
(-3640 3805);
DISPLAY 0.787234 (-3640 3805);
PAINT ORANGE (-3640 3805);
DISPLAY INVISIBLE (-3640 3805);
FORCEADD CAP_A..1
(-4050 3925);
FORCEPROP 1 LAST PACK_TYPE 0402V
J 0
(-4000 3725);
DISPLAY 0.617021 (-4000 3725);
PAINT SKYBLUE (-4000 3725);
FORCEPROP 1 LAST PART_NUMBER A36096-030
J 0
(-4000 3775);
DISPLAY 0.617021 (-4000 3775);
PAINT BLUE (-4000 3775);
FORCEPROP 1 LAST TOLERANCE 10%
J 0
(-4000 3875);
DISPLAY 0.617021 (-4000 3875);
PAINT SKYBLUE (-4000 3875);
FORCEPROP 1 LAST VALUE 0.1UF
J 0
(-4000 3975);
DISPLAY 0.617021 (-4000 3975);
PAINT SKYBLUE (-4000 3975);
FORCEPROP 1 LAST LOCATION C1C9
J 0
(-4000 4025);
DISPLAY 0.617021 (-4000 4025);
PAINT AQUA (-4000 4025);
FORCEPROP 1 LASTPIN (-4050 4025) $PN 1
J 0
(-4040 4005);
DISPLAY 0.617021 (-4040 4005);
PAINT WHITE (-4040 4005);
FORCEPROP 1 LASTPIN (-4050 3825) $PN 2
J 0
(-4040 3805);
DISPLAY 0.617021 (-4040 3805);
PAINT WHITE (-4040 3805);
FORCEPROP 1 LAST MATERIAL X7R
J 0
(-4000 3825);
DISPLAY 0.617021 (-4000 3825);
PAINT SKYBLUE (-4000 3825);
FORCEPROP 1 LAST VOLTAGE 16V
J 0
(-4000 3925);
DISPLAY 0.617021 (-4000 3925);
PAINT SKYBLUE (-4000 3925);
FORCEPROP 2 LAST SEC_TYPE 0402V
J 0
(-4000 4125);
DISPLAY 1.021277 (-4000 4125);
PAINT ORANGE (-4000 4125);
DISPLAY INVISIBLE (-4000 4125);
FORCEPROP 2 LAST SEC 1
J 0
(-4000 4125);
DISPLAY 0.680851 (-4000 4125);
PAINT MONO (-4000 4125);
DISPLAY INVISIBLE (-4000 4125);
FORCEPROP 1 LAST PATH I42
J 0
(-4000 4075);
DISPLAY 0.978723 (-4000 4075);
PAINT WHITE (-4000 4075);
DISPLAY INVISIBLE (-4000 4075);
FORCEPROP 2 LAST ROOM PVCCIN_CPU1_VR
J 0
(-4000 4075);
DISPLAY 1.361702 (-4000 4075);
PAINT WHITE (-4000 4075);
DISPLAY INVISIBLE (-4000 4075);
FORCEPROP 2 LAST CDS_SEC 1
J 0
(-4000 4075);
PAINT ORANGE (-4000 4075);
DISPLAY INVISIBLE (-4000 4075);
FORCEPROP 2 LAST CDS_LOCATION C1C9
J 0
(-4000 4025);
DISPLAY 0.617021 (-4000 4025);
PAINT AQUA (-4000 4025);
DISPLAY INVISIBLE (-4000 4025);
FORCEPROP 2 LAST CDS_LIB dev_discrete
J 0
(-4050 3925);
PAINT ORANGE (-4050 3925);
DISPLAY INVISIBLE (-4050 3925);
FORCEADD GND..1
(-4050 3725);
FORCEPROP 3 LASTPIN (-4050 3775) SIG_NAME GND\g
J 0
(-4040 3785);
DISPLAY 0.659574 (-4040 3785);
PAINT MONO (-4040 3785);
DISPLAY INVISIBLE (-4040 3785);
FORCEPROP 1 LAST HDL_POWER GND
J 0
(-4050 3875);
DISPLAY 1.170213 (-4050 3875);
PAINT GREEN (-4050 3875);
DISPLAY INVISIBLE (-4050 3875);
FORCEPROP 1 LAST BODY_TYPE PLUMBING
J 0
(-4095 3682);
DISPLAY 0.340426 (-4095 3682);
PAINT GREEN (-4095 3682);
DISPLAY INVISIBLE (-4095 3682);
FORCEPROP 1 LAST VOLTAGE 0
J 0
(-4050 3725);
PAINT SKYBLUE (-4050 3725);
DISPLAY INVISIBLE (-4050 3725);
FORCEPROP 2 LAST CDS_LIB mstr_symbols
J 0
(-4050 3725);
PAINT ORANGE (-4050 3725);
DISPLAY INVISIBLE (-4050 3725);
FORCEPROP 1 LAST PATH I43
J 0
(-3975 3725);
DISPLAY 0.872340 (-3975 3725);
PAINT AQUA (-3975 3725);
DISPLAY INVISIBLE (-3975 3725);
FORCEPROP 1 LAST SIZE 1B
J 0
(-3975 3675);
DISPLAY 1.170213 (-3975 3675);
PAINT AQUA (-3975 3675);
DISPLAY INVISIBLE (-3975 3675);
FORCEPROP 2 LAST ROOM PVCCIN_CPU1_VR
J 0
(-4625 3800);
DISPLAY 1.361702 (-4625 3800);
PAINT WHITE (-4625 3800);
DISPLAY INVISIBLE (-4625 3800);
FORCEADD GND..1
(-3175 1550);
FORCEPROP 3 LASTPIN (-3175 1600) SIG_NAME GND\g
J 0
(-3165 1610);
DISPLAY 0.659574 (-3165 1610);
PAINT MONO (-3165 1610);
DISPLAY INVISIBLE (-3165 1610);
FORCEPROP 1 LAST HDL_POWER GND
J 0
(-3175 1700);
DISPLAY 1.170213 (-3175 1700);
PAINT GREEN (-3175 1700);
DISPLAY INVISIBLE (-3175 1700);
FORCEPROP 1 LAST BODY_TYPE PLUMBING
J 0
(-3220 1507);
DISPLAY 0.340426 (-3220 1507);
PAINT GREEN (-3220 1507);
DISPLAY INVISIBLE (-3220 1507);
FORCEPROP 2 LAST CDS_LIB mstr_symbols
J 0
(-3175 1550);
PAINT ORANGE (-3175 1550);
DISPLAY INVISIBLE (-3175 1550);
FORCEPROP 1 LAST PATH I44
J 0
(-3100 1550);
DISPLAY 0.872340 (-3100 1550);
PAINT AQUA (-3100 1550);
DISPLAY INVISIBLE (-3100 1550);
FORCEPROP 1 LAST VOLTAGE 0
J 0
(-3175 1550);
PAINT SKYBLUE (-3175 1550);
DISPLAY INVISIBLE (-3175 1550);
FORCEPROP 1 LAST SIZE 1B
J 0
(-3100 1500);
DISPLAY 1.170213 (-3100 1500);
PAINT AQUA (-3100 1500);
DISPLAY INVISIBLE (-3100 1500);
FORCEPROP 2 LAST ROOM PVCCIN_CPU1_VR
J 0
(-3750 1625);
DISPLAY 1.361702 (-3750 1625);
PAINT WHITE (-3750 1625);
DISPLAY INVISIBLE (-3750 1625);
FORCEADD RES..2
(-4350 4275);
FORCEPROP 1 LAST PART_NUMBER G21497-005
J 0
(-4310 4150);
DISPLAY 0.617021 (-4310 4150);
PAINT BLUE (-4310 4150);
FORCEPROP 1 LAST LOCATION R1C14
J 0
(-4305 4400);
DISPLAY 0.617021 (-4305 4400);
PAINT AQUA (-4305 4400);
FORCEPROP 1 LASTPIN (-4350 4375) $PN 1
J 0
(-4345 4337);
DISPLAY 0.617021 (-4345 4337);
PAINT WHITE (-4345 4337);
FORCEPROP 1 LAST VALUE 0.0
J 0
(-4305 4350);
DISPLAY 0.617021 (-4305 4350);
PAINT SKYBLUE (-4305 4350);
FORCEPROP 1 LAST TOLERANCE 5%
J 0
(-4305 4300);
DISPLAY 0.617021 (-4305 4300);
PAINT SKYBLUE (-4305 4300);
FORCEPROP 1 LAST PACK_TYPE 0402
J 0
(-4310 4100);
DISPLAY 0.617021 (-4310 4100);
PAINT SKYBLUE (-4310 4100);
FORCEPROP 1 LAST MATERIAL CHIP
J 0
(-4310 4200);
DISPLAY 0.617021 (-4310 4200);
PAINT SKYBLUE (-4310 4200);
FORCEPROP 1 LAST WATTAGE 1/16W
J 0
(-4310 4250);
DISPLAY 0.617021 (-4310 4250);
PAINT SKYBLUE (-4310 4250);
FORCEPROP 1 LASTPIN (-4350 4175) $PN 2
J 0
(-4345 4185);
DISPLAY 0.617021 (-4345 4185);
PAINT WHITE (-4345 4185);
FORCEPROP 2 LAST ROOM PVCCIN_CPU1_VR
J 0
(-4300 4450);
DISPLAY 1.361702 (-4300 4450);
PAINT WHITE (-4300 4450);
DISPLAY INVISIBLE (-4300 4450);
FORCEPROP 1 LAST PATH I46
J 0
(-4300 4450);
DISPLAY 0.978723 (-4300 4450);
PAINT WHITE (-4300 4450);
DISPLAY INVISIBLE (-4300 4450);
FORCEPROP 2 LAST CDS_LOCATION R1C14
J 0
(-4305 4400);
DISPLAY 0.617021 (-4305 4400);
PAINT AQUA (-4305 4400);
DISPLAY INVISIBLE (-4305 4400);
FORCEPROP 2 LAST SEC 1
J 0
(-4300 4500);
PAINT MONO (-4300 4500);
DISPLAY INVISIBLE (-4300 4500);
FORCEPROP 2 LAST SEC_TYPE 0402
J 0
(-4300 4500);
DISPLAY 1.021277 (-4300 4500);
PAINT ORANGE (-4300 4500);
DISPLAY INVISIBLE (-4300 4500);
FORCEPROP 2 LAST CDS_LIB mstr_discrete
J 0
(-4350 4275);
PAINT ORANGE (-4350 4275);
DISPLAY INVISIBLE (-4350 4275);
FORCEADD PVCCIO_CPU1..1
(-5225 4875);
FORCEPROP 3 LASTPIN (-5225 4825) SIG_NAME PVCCIO_CPU1\g
J 0
(-5215 4835);
DISPLAY 0.659574 (-5215 4835);
PAINT MONO (-5215 4835);
DISPLAY INVISIBLE (-5215 4835);
FORCEPROP 1 LAST HDL_POWER PVCCIO_CPU1
J 1
(-5225 4925);
DISPLAY 0.872340 (-5225 4925);
PAINT GREEN (-5225 4925);
DISPLAY INVISIBLE (-5225 4925);
FORCEPROP 1 LAST BODY_TYPE PLUMBING
J 0
(-5270 4832);
DISPLAY 0.340426 (-5270 4832);
PAINT GREEN (-5270 4832);
DISPLAY INVISIBLE (-5270 4832);
FORCEPROP 2 LAST CDS_LIB mstr_symbols
J 0
(-5225 4875);
PAINT ORANGE (-5225 4875);
DISPLAY INVISIBLE (-5225 4875);
FORCEPROP 1 LAST PATH I47
J 0
(-5175 4900);
DISPLAY 0.872340 (-5175 4900);
PAINT AQUA (-5175 4900);
DISPLAY INVISIBLE (-5175 4900);
FORCEPROP 1 LAST VOLTAGE 1.1V
J 0
(-5270 4832);
DISPLAY 0.340426 (-5270 4832);
PAINT SKYBLUE (-5270 4832);
DISPLAY INVISIBLE (-5270 4832);
FORCEADD VCC_CORE..1
(-6150 4875);
FORCEPROP 3 LASTPIN (-6150 4825) SIG_NAME VR_FET_SW_P12V_STBY_PVCCIN_CPU1\g
J 0
(-6140 4835);
DISPLAY 0.659574 (-6140 4835);
PAINT MONO (-6140 4835);
DISPLAY INVISIBLE (-6140 4835);
FORCEPROP 1 LAST HDL_POWER VR_FET_SW_P12V_STBY_PVCCIN_CPU1
J 1
(-6150 4925);
DISPLAY 0.617021 (-6150 4925);
PAINT GREEN (-6150 4925);
FORCEPROP 1 LAST PATH I48
J 0
(-6100 4900);
DISPLAY 0.872340 (-6100 4900);
PAINT AQUA (-6100 4900);
DISPLAY INVISIBLE (-6100 4900);
FORCEPROP 0 LASTPIN (-6150 4825) VOLTAGE +3.3V
R 1
J 0
(-6150 4875);
DISPLAY 1.021277 (-6150 4875);
PAINT SKYBLUE (-6150 4875);
DISPLAY INVISIBLE (-6150 4875);
FORCEPROP 0 LAST VOLTAGE 12
J 0
(-6150 5025);
DISPLAY 1.021277 (-6150 5025);
PAINT SKYBLUE (-6150 5025);
DISPLAY INVISIBLE (-6150 5025);
FORCEPROP 2 LAST CDS_LIB mstr_symbols
J 0
(-6150 4875);
PAINT ORANGE (-6150 4875);
DISPLAY INVISIBLE (-6150 4875);
FORCEADD RES..2
(-6150 4575);
FORCEPROP 1 LAST PACK_TYPE 0402
J 0
(-6110 4400);
DISPLAY 0.617021 (-6110 4400);
PAINT SKYBLUE (-6110 4400);
FORCEPROP 1 LAST LOCATION R1C13
J 0
(-6105 4700);
DISPLAY 0.617021 (-6105 4700);
PAINT AQUA (-6105 4700);
FORCEPROP 1 LAST MATERIAL CHIP
J 0
(-6110 4500);
DISPLAY 0.617021 (-6110 4500);
PAINT SKYBLUE (-6110 4500);
FORCEPROP 1 LAST WATTAGE 1/16W
J 0
(-6110 4550);
DISPLAY 0.617021 (-6110 4550);
PAINT SKYBLUE (-6110 4550);
FORCEPROP 1 LASTPIN (-6150 4475) $PN 2
J 0
(-6145 4485);
DISPLAY 0.617021 (-6145 4485);
PAINT WHITE (-6145 4485);
FORCEPROP 1 LASTPIN (-6150 4675) $PN 1
J 0
(-6145 4637);
DISPLAY 0.617021 (-6145 4637);
PAINT WHITE (-6145 4637);
FORCEPROP 1 LAST TOLERANCE 1%
J 0
(-6105 4600);
DISPLAY 0.617021 (-6105 4600);
PAINT SKYBLUE (-6105 4600);
FORCEPROP 1 LAST VALUE 100.0K
J 0
(-6105 4650);
DISPLAY 0.617021 (-6105 4650);
PAINT SKYBLUE (-6105 4650);
FORCEPROP 1 LAST PART_NUMBER G21796-160
J 0
(-6110 4450);
DISPLAY 0.617021 (-6110 4450);
PAINT BLUE (-6110 4450);
FORCEPROP 2 LAST SEC_TYPE 0402
J 0
(-6100 4800);
DISPLAY 1.021277 (-6100 4800);
PAINT ORANGE (-6100 4800);
DISPLAY INVISIBLE (-6100 4800);
FORCEPROP 2 LAST SEC 1
J 0
(-6100 4800);
DISPLAY 0.680851 (-6100 4800);
PAINT MONO (-6100 4800);
DISPLAY INVISIBLE (-6100 4800);
FORCEPROP 2 LAST CDS_LOCATION R1C13
J 0
(-6105 4700);
DISPLAY 0.617021 (-6105 4700);
PAINT AQUA (-6105 4700);
DISPLAY INVISIBLE (-6105 4700);
FORCEPROP 1 LAST PATH I49
J 0
(-6100 4750);
DISPLAY 0.978723 (-6100 4750);
PAINT WHITE (-6100 4750);
DISPLAY INVISIBLE (-6100 4750);
FORCEPROP 2 LAST ROOM PVCCIN_CPU1_VR
J 0
(-6100 4750);
DISPLAY 1.361702 (-6100 4750);
PAINT WHITE (-6100 4750);
DISPLAY INVISIBLE (-6100 4750);
FORCEPROP 2 LAST CDS_LIB mstr_discrete
J 0
(-6150 4575);
PAINT ORANGE (-6150 4575);
DISPLAY INVISIBLE (-6150 4575);
FORCEADD OFFPAGE..2
(-550 3375);
FORCEPROP 2 LAST $XR0 190 
J 0
(-361 3375);
DISPLAY 0.638298 (-361 3375);
PAINT MONO (-361 3375);
FORCEPROP 1 LAST COMMENT_BODY TRUE
J 0
(-595 3280);
DISPLAY 1.170213 (-595 3280);
PAINT PEACH (-595 3280);
DISPLAY INVISIBLE (-595 3280);
FORCEPROP 1 LAST OFFPAGE TRUE
J 0
(-225 3250);
DISPLAY 1.170213 (-225 3250);
PAINT GREEN (-225 3250);
DISPLAY INVISIBLE (-225 3250);
FORCEPROP 2 LAST PATH I5
J 0
(-375 3450);
DISPLAY 1.021277 (-375 3450);
PAINT ORANGE (-375 3450);
DISPLAY INVISIBLE (-375 3450);
FORCEPROP 2 LAST CDS_LIB mstr_standard
J 0
(-550 3375);
PAINT ORANGE (-550 3375);
DISPLAY INVISIBLE (-550 3375);
FORCEPROP 2 LAST ROOM PVCCIN_CPU1_VR
J 0
(-975 3450);
DISPLAY 1.361702 (-975 3450);
PAINT WHITE (-975 3450);
DISPLAY INVISIBLE (-975 3450);
FORCEADD OFFPAGE..2
R 2
(-7500 4425);
FORCEPROP 2 LAST $XR0 206 
J 0
(-7785 4425);
DISPLAY 0.638298 (-7785 4425);
PAINT MONO (-7785 4425);
FORCEPROP 1 LAST COMMENT_BODY TRUE
J 2
(-7455 4330);
DISPLAY 1.170213 (-7455 4330);
PAINT PEACH (-7455 4330);
DISPLAY INVISIBLE (-7455 4330);
FORCEPROP 1 LAST OFFPAGE TRUE
J 2
(-7825 4300);
DISPLAY 1.170213 (-7825 4300);
PAINT GREEN (-7825 4300);
DISPLAY INVISIBLE (-7825 4300);
FORCEPROP 2 LAST CDS_LIB mstr_standard
J 2
(-7500 4425);
PAINT ORANGE (-7500 4425);
DISPLAY INVISIBLE (-7500 4425);
FORCEPROP 2 LAST ROOM PVCCIN_CPU1_VR
J 0
(-8050 4500);
DISPLAY 1.361702 (-8050 4500);
PAINT WHITE (-8050 4500);
DISPLAY INVISIBLE (-8050 4500);
FORCEPROP 2 LAST PATH I50
J 0
(-7775 4475);
DISPLAY 1.021277 (-7775 4475);
PAINT ORANGE (-7775 4475);
DISPLAY INVISIBLE (-7775 4475);
FORCEADD RES..2
(-5650 4450);
FORCEPROP 1 LAST PART_NUMBER G21796-047
J 0
(-5610 4325);
DISPLAY 0.617021 (-5610 4325);
PAINT BLUE (-5610 4325);
FORCEPROP 1 LAST LOCATION R9P2
J 0
(-5605 4575);
DISPLAY 0.617021 (-5605 4575);
PAINT AQUA (-5605 4575);
FORCEPROP 1 LAST MATERIAL CHIP
J 0
(-5610 4375);
DISPLAY 0.617021 (-5610 4375);
PAINT SKYBLUE (-5610 4375);
FORCEPROP 1 LAST WATTAGE 1/16W
J 0
(-5610 4425);
DISPLAY 0.617021 (-5610 4425);
PAINT SKYBLUE (-5610 4425);
FORCEPROP 1 LASTPIN (-5650 4350) $PN 2
J 0
(-5645 4360);
DISPLAY 0.617021 (-5645 4360);
PAINT WHITE (-5645 4360);
FORCEPROP 1 LASTPIN (-5650 4550) $PN 1
J 0
(-5645 4512);
DISPLAY 0.617021 (-5645 4512);
PAINT WHITE (-5645 4512);
FORCEPROP 1 LAST TOLERANCE 1%
J 0
(-5605 4475);
DISPLAY 0.617021 (-5605 4475);
PAINT SKYBLUE (-5605 4475);
FORCEPROP 1 LAST VALUE 49.9
J 0
(-5605 4525);
DISPLAY 0.617021 (-5605 4525);
PAINT SKYBLUE (-5605 4525);
FORCEPROP 1 LAST PACK_TYPE 0402
J 0
(-5610 4275);
DISPLAY 0.617021 (-5610 4275);
PAINT SKYBLUE (-5610 4275);
FORCEPROP 2 LAST SEC 1
J 0
(-5600 4675);
DISPLAY 0.680851 (-5600 4675);
PAINT MONO (-5600 4675);
DISPLAY INVISIBLE (-5600 4675);
FORCEPROP 2 LAST SEC_TYPE 0402
J 0
(-5600 4675);
DISPLAY 1.021277 (-5600 4675);
PAINT ORANGE (-5600 4675);
DISPLAY INVISIBLE (-5600 4675);
FORCEPROP 1 LAST PATH I53
J 0
(-5600 4625);
DISPLAY 0.978723 (-5600 4625);
PAINT WHITE (-5600 4625);
DISPLAY INVISIBLE (-5600 4625);
FORCEPROP 2 LAST ROOM PVCCIN_CPU1_VR
J 0
(-5600 4625);
DISPLAY 1.361702 (-5600 4625);
PAINT WHITE (-5600 4625);
DISPLAY INVISIBLE (-5600 4625);
FORCEPROP 2 LAST CDS_LOCATION R9P2
J 0
(-5605 4575);
DISPLAY 0.617021 (-5605 4575);
PAINT AQUA (-5605 4575);
DISPLAY INVISIBLE (-5605 4575);
FORCEPROP 2 LAST CDS_LIB mstr_discrete
J 0
(-5650 4450);
PAINT ORANGE (-5650 4450);
DISPLAY INVISIBLE (-5650 4450);
FORCEADD RES..1
(-5375 3900);
FORCEPROP 1 LAST TOLERANCE 1%
J 0
(-5325 3975);
DISPLAY 0.617021 (-5325 3975);
PAINT SKYBLUE (-5325 3975);
FORCEPROP 1 LAST LOCATION R1D9
J 0
(-5475 4075);
DISPLAY 0.617021 (-5475 4075);
PAINT AQUA (-5475 4075);
FORCEPROP 1 LASTPIN (-5475 3900) $PN 1
J 0
(-5463 3912);
DISPLAY 0.617021 (-5463 3912);
PAINT WHITE (-5463 3912);
FORCEPROP 1 LAST PART_NUMBER G21796-009
J 0
(-5475 4025);
DISPLAY 0.617021 (-5475 4025);
PAINT BLUE (-5475 4025);
FORCEPROP 1 LAST VALUE 150.0
J 2
(-5375 3975);
DISPLAY 0.617021 (-5375 3975);
PAINT SKYBLUE (-5375 3975);
FORCEPROP 1 LASTPIN (-5275 3900) $PN 2
J 0
(-5313 3912);
DISPLAY 0.617021 (-5313 3912);
PAINT WHITE (-5313 3912);
FORCEPROP 1 LAST MATERIAL CHIP
J 0
(-5275 3925);
DISPLAY 0.617021 (-5275 3925);
PAINT SKYBLUE (-5275 3925);
FORCEPROP 1 LAST WATTAGE 1/16W
J 2
(-5325 3925);
DISPLAY 0.617021 (-5325 3925);
PAINT SKYBLUE (-5325 3925);
FORCEPROP 1 LAST PACK_TYPE 0402
J 0
(-5250 3975);
DISPLAY 0.617021 (-5250 3975);
PAINT SKYBLUE (-5250 3975);
FORCEPROP 2 LAST ROOM PVCCIN_CPU1_VR
J 0
(-5475 4125);
DISPLAY 1.361702 (-5475 4125);
PAINT WHITE (-5475 4125);
DISPLAY INVISIBLE (-5475 4125);
FORCEPROP 2 LAST $SEC 1
J 0
(-5475 4125);
PAINT MONO (-5475 4125);
DISPLAY INVISIBLE (-5475 4125);
FORCEPROP 2 LAST CDS_SEC 1
J 0
(-5475 4125);
PAINT MONO (-5475 4125);
DISPLAY INVISIBLE (-5475 4125);
FORCEPROP 2 LAST CDS_LOCATION R1D9
J 0
(-5475 4075);
DISPLAY 0.617021 (-5475 4075);
PAINT AQUA (-5475 4075);
DISPLAY INVISIBLE (-5475 4075);
FORCEPROP 2 LAST CDS_LIB mstr_discrete
J 0
(-5375 3900);
PAINT ORANGE (-5375 3900);
DISPLAY INVISIBLE (-5375 3900);
FORCEPROP 1 LAST PATH I54
J 0
(-5425 4050);
DISPLAY 0.978723 (-5425 4050);
PAINT WHITE (-5425 4050);
DISPLAY INVISIBLE (-5425 4050);
FORCEADD RES..2
(-6150 4225);
FORCEPROP 1 LAST MATERIAL CHIP
J 0
(-6110 4150);
DISPLAY 0.617021 (-6110 4150);
PAINT SKYBLUE (-6110 4150);
FORCEPROP 1 LAST PART_NUMBER G21796-003
J 0
(-6110 4100);
DISPLAY 0.617021 (-6110 4100);
PAINT BLUE (-6110 4100);
FORCEPROP 1 LASTPIN (-6150 4125) $PN 2
J 0
(-6145 4135);
DISPLAY 0.617021 (-6145 4135);
PAINT WHITE (-6145 4135);
FORCEPROP 1 LASTPIN (-6150 4325) $PN 1
J 0
(-6145 4287);
DISPLAY 0.617021 (-6145 4287);
PAINT WHITE (-6145 4287);
FORCEPROP 1 LAST PACK_TYPE 0402
J 0
(-6110 4050);
DISPLAY 0.617021 (-6110 4050);
PAINT SKYBLUE (-6110 4050);
FORCEPROP 1 LAST TOLERANCE 1%
J 0
(-6105 4250);
DISPLAY 0.617021 (-6105 4250);
PAINT SKYBLUE (-6105 4250);
FORCEPROP 1 LAST VALUE 1.5K
J 0
(-6105 4300);
DISPLAY 0.617021 (-6105 4300);
PAINT SKYBLUE (-6105 4300);
FORCEPROP 1 LAST LOCATION R1C16
J 0
(-6105 4350);
DISPLAY 0.617021 (-6105 4350);
PAINT AQUA (-6105 4350);
FORCEPROP 1 LAST WATTAGE 1/16W
J 0
(-6110 4200);
DISPLAY 0.617021 (-6110 4200);
PAINT SKYBLUE (-6110 4200);
FORCEPROP 2 LAST SEC 1
J 0
(-6100 4450);
DISPLAY 0.680851 (-6100 4450);
PAINT MONO (-6100 4450);
DISPLAY INVISIBLE (-6100 4450);
FORCEPROP 2 LAST CDS_LOCATION R1C16
J 0
(-6105 4350);
DISPLAY 0.617021 (-6105 4350);
PAINT AQUA (-6105 4350);
DISPLAY INVISIBLE (-6105 4350);
FORCEPROP 1 LAST PATH I56
J 0
(-6100 4400);
DISPLAY 0.978723 (-6100 4400);
PAINT WHITE (-6100 4400);
DISPLAY INVISIBLE (-6100 4400);
FORCEPROP 2 LAST ROOM PVCCIN_CPU1_VR
J 0
(-6100 4400);
DISPLAY 1.361702 (-6100 4400);
PAINT WHITE (-6100 4400);
DISPLAY INVISIBLE (-6100 4400);
FORCEPROP 2 LAST SEC_TYPE 0402
J 0
(-6100 4450);
DISPLAY 1.021277 (-6100 4450);
PAINT ORANGE (-6100 4450);
DISPLAY INVISIBLE (-6100 4450);
FORCEPROP 2 LAST CDS_LIB mstr_discrete
J 0
(-6150 4225);
PAINT ORANGE (-6150 4225);
DISPLAY INVISIBLE (-6150 4225);
FORCEADD GND..1
(-6150 3975);
FORCEPROP 3 LASTPIN (-6150 4025) SIG_NAME GND\g
J 0
(-6140 4035);
DISPLAY 0.659574 (-6140 4035);
PAINT MONO (-6140 4035);
DISPLAY INVISIBLE (-6140 4035);
FORCEPROP 1 LAST HDL_POWER GND
J 0
(-6150 4125);
DISPLAY 1.170213 (-6150 4125);
PAINT GREEN (-6150 4125);
DISPLAY INVISIBLE (-6150 4125);
FORCEPROP 1 LAST BODY_TYPE PLUMBING
J 0
(-6195 3932);
DISPLAY 0.340426 (-6195 3932);
PAINT GREEN (-6195 3932);
DISPLAY INVISIBLE (-6195 3932);
FORCEPROP 2 LAST ROOM PVCCIN_CPU1_VR
J 0
(-6725 4050);
DISPLAY 1.361702 (-6725 4050);
PAINT WHITE (-6725 4050);
DISPLAY INVISIBLE (-6725 4050);
FORCEPROP 1 LAST SIZE 1B
J 0
(-6075 3925);
DISPLAY 1.170213 (-6075 3925);
PAINT AQUA (-6075 3925);
DISPLAY INVISIBLE (-6075 3925);
FORCEPROP 1 LAST PATH I57
J 0
(-6075 3975);
DISPLAY 0.872340 (-6075 3975);
PAINT AQUA (-6075 3975);
DISPLAY INVISIBLE (-6075 3975);
FORCEPROP 2 LAST CDS_LIB mstr_symbols
J 0
(-6150 3975);
PAINT ORANGE (-6150 3975);
DISPLAY INVISIBLE (-6150 3975);
FORCEPROP 1 LAST VOLTAGE 0
J 0
(-6150 3975);
PAINT SKYBLUE (-6150 3975);
DISPLAY INVISIBLE (-6150 3975);
FORCEADD RES..2
R 2
(-3150 4000);
FORCEPROP 1 LAST PACK_TYPE 0402
J 2
(-3190 3825);
DISPLAY 0.617021 (-3190 3825);
PAINT SKYBLUE (-3190 3825);
FORCEPROP 1 LAST PART_NUMBER G21796-026
J 2
(-3190 3875);
DISPLAY 0.617021 (-3190 3875);
PAINT BLUE (-3190 3875);
FORCEPROP 1 LAST MATERIAL CHIP
J 2
(-3190 3925);
DISPLAY 0.617021 (-3190 3925);
PAINT SKYBLUE (-3190 3925);
FORCEPROP 1 LAST WATTAGE 1/16W
J 2
(-3190 3975);
DISPLAY 0.617021 (-3190 3975);
PAINT SKYBLUE (-3190 3975);
FORCEPROP 1 LAST VALUE 1.00K
J 2
(-3195 4075);
DISPLAY 0.617021 (-3195 4075);
PAINT SKYBLUE (-3195 4075);
FORCEPROP 1 LAST LOCATION R1D6
J 2
(-3195 4125);
DISPLAY 0.617021 (-3195 4125);
PAINT AQUA (-3195 4125);
FORCEPROP 1 LASTPIN (-3150 4100) $PN 1
J 2
(-3155 4062);
DISPLAY 0.617021 (-3155 4062);
PAINT WHITE (-3155 4062);
FORCEPROP 1 LAST TOLERANCE 1%
J 2
(-3195 4025);
DISPLAY 0.617021 (-3195 4025);
PAINT SKYBLUE (-3195 4025);
FORCEPROP 1 LASTPIN (-3150 3900) $PN 2
J 2
(-3155 3910);
DISPLAY 0.617021 (-3155 3910);
PAINT WHITE (-3155 3910);
FORCEPROP 2 LAST CDS_LIB mstr_discrete
J 0
(-3150 4000);
PAINT ORANGE (-3150 4000);
DISPLAY INVISIBLE (-3150 4000);
FORCEPROP 2 LAST SEC_TYPE 0402
J 2
(-3200 4225);
DISPLAY 1.021277 (-3200 4225);
PAINT ORANGE (-3200 4225);
DISPLAY INVISIBLE (-3200 4225);
FORCEPROP 2 LAST SEC 1
J 2
(-3200 4225);
DISPLAY 0.680851 (-3200 4225);
PAINT MONO (-3200 4225);
DISPLAY INVISIBLE (-3200 4225);
FORCEPROP 2 LAST CDS_LOCATION R1D6
J 2
(-3195 4125);
DISPLAY 0.617021 (-3195 4125);
PAINT AQUA (-3195 4125);
DISPLAY INVISIBLE (-3195 4125);
FORCEPROP 1 LAST PATH I6
J 2
(-3200 4175);
DISPLAY 0.978723 (-3200 4175);
PAINT WHITE (-3200 4175);
DISPLAY INVISIBLE (-3200 4175);
FORCEPROP 2 LAST ROOM PVCCIN_CPU1_VR
J 2
(-3200 4175);
DISPLAY 1.361702 (-3200 4175);
PAINT WHITE (-3200 4175);
DISPLAY INVISIBLE (-3200 4175);
FORCEADD GND..1
(-4500 575);
FORCEPROP 3 LASTPIN (-4500 625) SIG_NAME GND\g
J 0
(-4490 635);
DISPLAY 0.659574 (-4490 635);
PAINT MONO (-4490 635);
DISPLAY INVISIBLE (-4490 635);
FORCEPROP 1 LAST HDL_POWER GND
J 0
(-4500 725);
DISPLAY 1.170213 (-4500 725);
PAINT GREEN (-4500 725);
DISPLAY INVISIBLE (-4500 725);
FORCEPROP 1 LAST BODY_TYPE PLUMBING
J 0
(-4545 532);
DISPLAY 0.340426 (-4545 532);
PAINT GREEN (-4545 532);
DISPLAY INVISIBLE (-4545 532);
FORCEPROP 1 LAST VOLTAGE 0
J 0
(-4500 575);
PAINT SKYBLUE (-4500 575);
DISPLAY INVISIBLE (-4500 575);
FORCEPROP 2 LAST CDS_LIB mstr_symbols
J 0
(-4500 575);
PAINT ORANGE (-4500 575);
DISPLAY INVISIBLE (-4500 575);
FORCEPROP 1 LAST SIZE 1B
J 0
(-4425 525);
DISPLAY 1.170213 (-4425 525);
PAINT AQUA (-4425 525);
DISPLAY INVISIBLE (-4425 525);
FORCEPROP 1 LAST PATH I65
J 0
(-4425 575);
DISPLAY 0.872340 (-4425 575);
PAINT AQUA (-4425 575);
DISPLAY INVISIBLE (-4425 575);
FORCEPROP 2 LAST ROOM PVCCIN_CPU1_VR
J 0
(-5075 650);
DISPLAY 1.361702 (-5075 650);
PAINT WHITE (-5075 650);
DISPLAY INVISIBLE (-5075 650);
FORCEADD GND..1
(-4825 525);
FORCEPROP 3 LASTPIN (-4825 575) SIG_NAME GND\g
J 0
(-4815 585);
DISPLAY 0.659574 (-4815 585);
PAINT MONO (-4815 585);
DISPLAY INVISIBLE (-4815 585);
FORCEPROP 1 LAST HDL_POWER GND
J 0
(-4825 675);
DISPLAY 1.170213 (-4825 675);
PAINT GREEN (-4825 675);
DISPLAY INVISIBLE (-4825 675);
FORCEPROP 1 LAST BODY_TYPE PLUMBING
J 0
(-4870 482);
DISPLAY 0.340426 (-4870 482);
PAINT GREEN (-4870 482);
DISPLAY INVISIBLE (-4870 482);
FORCEPROP 1 LAST VOLTAGE 0
J 0
(-4825 525);
PAINT SKYBLUE (-4825 525);
DISPLAY INVISIBLE (-4825 525);
FORCEPROP 2 LAST CDS_LIB mstr_symbols
J 0
(-4825 525);
PAINT ORANGE (-4825 525);
DISPLAY INVISIBLE (-4825 525);
FORCEPROP 1 LAST PATH I67
J 0
(-4750 525);
DISPLAY 0.872340 (-4750 525);
PAINT AQUA (-4750 525);
DISPLAY INVISIBLE (-4750 525);
FORCEPROP 1 LAST SIZE 1B
J 0
(-4750 475);
DISPLAY 1.170213 (-4750 475);
PAINT AQUA (-4750 475);
DISPLAY INVISIBLE (-4750 475);
FORCEPROP 2 LAST ROOM PVCCIN_CPU1_VR
J 0
(-5400 600);
DISPLAY 1.361702 (-5400 600);
PAINT WHITE (-5400 600);
DISPLAY INVISIBLE (-5400 600);
FORCEADD CAP..1
(-5650 2075);
FORCEPROP 1 LAST LOCATION C1C16
J 0
(-5900 2125);
DISPLAY 0.617021 (-5900 2125);
PAINT AQUA (-5900 2125);
FORCEPROP 1 LASTPIN (-5650 2175) $PN 1
J 0
(-5640 2155);
DISPLAY 0.617021 (-5640 2155);
PAINT WHITE (-5640 2155);
FORCEPROP 1 LASTPIN (-5650 1975) $PN 2
J 0
(-5640 1955);
DISPLAY 0.617021 (-5640 1955);
PAINT WHITE (-5640 1955);
FORCEPROP 1 LAST VOLTAGE 50V
J 0
(-6150 1950);
DISPLAY 0.617021 (-6150 1950);
PAINT SKYBLUE (-6150 1950);
FORCEPROP 1 LAST MATERIAL X7R
J 0
(-6000 1950);
DISPLAY 0.617021 (-6000 1950);
PAINT SKYBLUE (-6000 1950);
FORCEPROP 1 LAST VALUE 220PF
J 0
(-6025 2025);
DISPLAY 0.617021 (-6025 2025);
PAINT SKYBLUE (-6025 2025);
FORCEPROP 1 LAST TOLERANCE 10%
J 0
(-5825 2025);
DISPLAY 0.617021 (-5825 2025);
PAINT SKYBLUE (-5825 2025);
FORCEPROP 1 LAST PACK_TYPE 0402LF
J 0
(-5875 1950);
DISPLAY 0.617021 (-5875 1950);
PAINT SKYBLUE (-5875 1950);
FORCEPROP 1 LAST PART_NUMBER A36096-050
J 0
(-6025 2075);
DISPLAY 0.617021 (-6025 2075);
PAINT BLUE (-6025 2075);
FORCEPROP 2 LAST SEC 1
J 0
(-5600 2275);
DISPLAY 0.680851 (-5600 2275);
PAINT MONO (-5600 2275);
DISPLAY INVISIBLE (-5600 2275);
FORCEPROP 2 LAST NO_XNET_CONNECTION 1
J 0
(-5600 2275);
PAINT MONO (-5600 2275);
DISPLAY INVISIBLE (-5600 2275);
FORCEPROP 1 LAST PATH I68
J 0
(-5600 2225);
DISPLAY 0.978723 (-5600 2225);
PAINT WHITE (-5600 2225);
DISPLAY INVISIBLE (-5600 2225);
FORCEPROP 2 LAST SEC_TYPE 0402LF
J 0
(-5600 2275);
DISPLAY 1.021277 (-5600 2275);
PAINT ORANGE (-5600 2275);
DISPLAY INVISIBLE (-5600 2275);
FORCEPROP 2 LAST CDS_LIB mstr_discrete
J 0
(-5650 2075);
PAINT ORANGE (-5650 2075);
DISPLAY INVISIBLE (-5650 2075);
FORCEPROP 2 LAST CDS_LOCATION C1C16
J 0
(-5900 2125);
DISPLAY 0.617021 (-5900 2125);
PAINT AQUA (-5900 2125);
DISPLAY INVISIBLE (-5900 2125);
FORCEPROP 2 LAST ROOM PVCCIN_CPU1_VR
J 0
(-5900 2175);
DISPLAY 1.361702 (-5900 2175);
PAINT WHITE (-5900 2175);
DISPLAY INVISIBLE (-5900 2175);
FORCEADD CAP..1
(-5925 1275);
FORCEPROP 1 LASTPIN (-5925 1175) $PN 2
J 0
(-5915 1155);
DISPLAY 0.617021 (-5915 1155);
PAINT WHITE (-5915 1155);
FORCEPROP 1 LASTPIN (-5925 1375) $PN 1
J 0
(-5915 1355);
DISPLAY 0.617021 (-5915 1355);
PAINT WHITE (-5915 1355);
FORCEPROP 1 LAST LOCATION C1C10
J 0
(-5875 1375);
DISPLAY 0.617021 (-5875 1375);
PAINT AQUA (-5875 1375);
FORCEPROP 1 LAST VOLTAGE 50V
J 0
(-5875 1275);
DISPLAY 0.617021 (-5875 1275);
PAINT SKYBLUE (-5875 1275);
FORCEPROP 1 LAST MATERIAL X7R
J 0
(-5750 1275);
DISPLAY 0.617021 (-5750 1275);
PAINT SKYBLUE (-5750 1275);
FORCEPROP 1 LAST TOLERANCE 10%
J 0
(-5700 1325);
DISPLAY 0.617021 (-5700 1325);
PAINT SKYBLUE (-5700 1325);
FORCEPROP 1 LAST VALUE 220PF
J 0
(-5875 1325);
DISPLAY 0.617021 (-5875 1325);
PAINT SKYBLUE (-5875 1325);
FORCEPROP 1 LAST PACK_TYPE 0402LF
J 0
(-5875 1175);
DISPLAY 0.617021 (-5875 1175);
PAINT SKYBLUE (-5875 1175);
FORCEPROP 1 LAST PART_NUMBER A36096-050
J 0
(-5875 1225);
DISPLAY 0.617021 (-5875 1225);
PAINT BLUE (-5875 1225);
FORCEPROP 2 LAST SEC 1
J 0
(-5875 1475);
DISPLAY 0.680851 (-5875 1475);
PAINT MONO (-5875 1475);
DISPLAY INVISIBLE (-5875 1475);
FORCEPROP 2 LAST SEC_TYPE 0402LF
J 0
(-5875 1475);
DISPLAY 1.021277 (-5875 1475);
PAINT ORANGE (-5875 1475);
DISPLAY INVISIBLE (-5875 1475);
FORCEPROP 2 LAST CDS_LOCATION C1C10
J 0
(-5875 1375);
DISPLAY 0.617021 (-5875 1375);
PAINT AQUA (-5875 1375);
DISPLAY INVISIBLE (-5875 1375);
FORCEPROP 1 LAST PATH I69
J 0
(-5875 1425);
DISPLAY 0.978723 (-5875 1425);
PAINT WHITE (-5875 1425);
DISPLAY INVISIBLE (-5875 1425);
FORCEPROP 2 LAST ROOM PVCCIN_CPU1_VR
J 0
(-5875 1425);
DISPLAY 1.361702 (-5875 1425);
PAINT WHITE (-5875 1425);
DISPLAY INVISIBLE (-5875 1425);
FORCEPROP 2 LAST CDS_LIB mstr_discrete
J 0
(-5925 1275);
PAINT ORANGE (-5925 1275);
DISPLAY INVISIBLE (-5925 1275);
FORCEADD GND..1
(-5925 475);
FORCEPROP 3 LASTPIN (-5925 525) SIG_NAME GND\g
J 0
(-5915 535);
DISPLAY 0.659574 (-5915 535);
PAINT MONO (-5915 535);
DISPLAY INVISIBLE (-5915 535);
FORCEPROP 1 LAST HDL_POWER GND
J 0
(-5925 625);
DISPLAY 1.170213 (-5925 625);
PAINT GREEN (-5925 625);
DISPLAY INVISIBLE (-5925 625);
FORCEPROP 1 LAST BODY_TYPE PLUMBING
J 0
(-5970 432);
DISPLAY 0.340426 (-5970 432);
PAINT GREEN (-5970 432);
DISPLAY INVISIBLE (-5970 432);
FORCEPROP 1 LAST PATH I70
J 0
(-5850 475);
DISPLAY 0.872340 (-5850 475);
PAINT AQUA (-5850 475);
DISPLAY INVISIBLE (-5850 475);
FORCEPROP 1 LAST SIZE 1B
J 0
(-5850 425);
DISPLAY 1.170213 (-5850 425);
PAINT AQUA (-5850 425);
DISPLAY INVISIBLE (-5850 425);
FORCEPROP 2 LAST CDS_LIB mstr_symbols
J 0
(-5925 475);
PAINT ORANGE (-5925 475);
DISPLAY INVISIBLE (-5925 475);
FORCEPROP 1 LAST VOLTAGE 0
J 0
(-5925 475);
PAINT SKYBLUE (-5925 475);
DISPLAY INVISIBLE (-5925 475);
FORCEPROP 2 LAST ROOM PVCCIN_CPU1_VR
J 0
(-6500 550);
DISPLAY 1.361702 (-6500 550);
PAINT WHITE (-6500 550);
DISPLAY INVISIBLE (-6500 550);
FORCEADD CAP..1
R 2
(-6150 650);
FORCEPROP 1 LASTPIN (-6150 550) $PN 2
J 2
(-6160 530);
DISPLAY 0.617021 (-6160 530);
PAINT WHITE (-6160 530);
FORCEPROP 1 LAST VOLTAGE 50V
J 2
(-6200 650);
DISPLAY 0.617021 (-6200 650);
PAINT SKYBLUE (-6200 650);
FORCEPROP 1 LAST VALUE 220PF
J 2
(-6200 700);
DISPLAY 0.617021 (-6200 700);
PAINT SKYBLUE (-6200 700);
FORCEPROP 1 LAST TOLERANCE 10%
J 2
(-6375 700);
DISPLAY 0.617021 (-6375 700);
PAINT SKYBLUE (-6375 700);
FORCEPROP 1 LAST PART_NUMBER A36096-050
J 2
(-6200 600);
DISPLAY 0.617021 (-6200 600);
PAINT BLUE (-6200 600);
FORCEPROP 1 LASTPIN (-6150 750) $PN 1
J 2
(-6160 730);
DISPLAY 0.617021 (-6160 730);
PAINT WHITE (-6160 730);
FORCEPROP 1 LAST MATERIAL X7R
J 2
(-6325 650);
DISPLAY 0.617021 (-6325 650);
PAINT SKYBLUE (-6325 650);
FORCEPROP 1 LAST LOCATION C1C11
J 2
(-6200 750);
DISPLAY 0.617021 (-6200 750);
PAINT AQUA (-6200 750);
FORCEPROP 1 LAST PACK_TYPE 0402LF
J 2
(-6200 550);
DISPLAY 0.617021 (-6200 550);
PAINT SKYBLUE (-6200 550);
FORCEPROP 2 LAST CDS_LIB mstr_discrete
J 2
(-6150 650);
PAINT ORANGE (-6150 650);
DISPLAY INVISIBLE (-6150 650);
FORCEPROP 2 LAST SEC_TYPE 0402LF
J 0
(-6200 850);
DISPLAY 1.021277 (-6200 850);
PAINT ORANGE (-6200 850);
DISPLAY INVISIBLE (-6200 850);
FORCEPROP 2 LAST SEC 1
J 0
(-6200 850);
DISPLAY 0.680851 (-6200 850);
PAINT MONO (-6200 850);
DISPLAY INVISIBLE (-6200 850);
FORCEPROP 2 LAST CDS_LOCATION C1C11
J 2
(-6200 750);
DISPLAY 0.617021 (-6200 750);
PAINT AQUA (-6200 750);
DISPLAY INVISIBLE (-6200 750);
FORCEPROP 1 LAST PATH I71
J 2
(-6200 800);
DISPLAY 0.978723 (-6200 800);
PAINT WHITE (-6200 800);
DISPLAY INVISIBLE (-6200 800);
FORCEPROP 2 LAST ROOM PVCCIN_CPU1_VR
J 0
(-6200 800);
DISPLAY 1.361702 (-6200 800);
PAINT WHITE (-6200 800);
DISPLAY INVISIBLE (-6200 800);
FORCEADD GND..1
(-6150 475);
FORCEPROP 3 LASTPIN (-6150 525) SIG_NAME GND\g
J 0
(-6140 535);
DISPLAY 0.659574 (-6140 535);
PAINT MONO (-6140 535);
DISPLAY INVISIBLE (-6140 535);
FORCEPROP 1 LAST HDL_POWER GND
J 0
(-6150 625);
DISPLAY 1.170213 (-6150 625);
PAINT GREEN (-6150 625);
DISPLAY INVISIBLE (-6150 625);
FORCEPROP 1 LAST BODY_TYPE PLUMBING
J 0
(-6195 432);
DISPLAY 0.340426 (-6195 432);
PAINT GREEN (-6195 432);
DISPLAY INVISIBLE (-6195 432);
FORCEPROP 1 LAST PATH I72
J 0
(-6075 475);
DISPLAY 0.872340 (-6075 475);
PAINT AQUA (-6075 475);
DISPLAY INVISIBLE (-6075 475);
FORCEPROP 1 LAST SIZE 1B
J 0
(-6075 425);
DISPLAY 1.170213 (-6075 425);
PAINT AQUA (-6075 425);
DISPLAY INVISIBLE (-6075 425);
FORCEPROP 1 LAST VOLTAGE 0
J 0
(-6150 475);
PAINT SKYBLUE (-6150 475);
DISPLAY INVISIBLE (-6150 475);
FORCEPROP 2 LAST CDS_LIB mstr_symbols
J 0
(-6150 475);
PAINT ORANGE (-6150 475);
DISPLAY INVISIBLE (-6150 475);
FORCEPROP 2 LAST ROOM PVCCIN_CPU1_VR
J 0
(-6725 550);
DISPLAY 1.361702 (-6725 550);
PAINT WHITE (-6725 550);
DISPLAY INVISIBLE (-6725 550);
FORCEADD GND..1
(-6750 4025);
FORCEPROP 3 LASTPIN (-6750 4075) SIG_NAME GND\g
J 0
(-6740 4085);
DISPLAY 0.659574 (-6740 4085);
PAINT MONO (-6740 4085);
DISPLAY INVISIBLE (-6740 4085);
FORCEPROP 1 LAST VOLTAGE 0
J 0
(-6750 4025);
PAINT SKYBLUE (-6750 4025);
DISPLAY INVISIBLE (-6750 4025);
FORCEPROP 2 LAST CDS_LIB mstr_symbols
J 0
(-6750 4025);
PAINT ORANGE (-6750 4025);
DISPLAY INVISIBLE (-6750 4025);
FORCEPROP 1 LAST SIZE 1B
J 0
(-6675 3975);
DISPLAY 1.170213 (-6675 3975);
PAINT AQUA (-6675 3975);
DISPLAY INVISIBLE (-6675 3975);
FORCEPROP 1 LAST PATH I74
J 0
(-6675 4025);
DISPLAY 0.872340 (-6675 4025);
PAINT AQUA (-6675 4025);
DISPLAY INVISIBLE (-6675 4025);
FORCEPROP 2 LAST ROOM PVCCIN_CPU1_VR
J 0
(-7325 4100);
DISPLAY 1.361702 (-7325 4100);
PAINT WHITE (-7325 4100);
DISPLAY INVISIBLE (-7325 4100);
FORCEPROP 1 LAST BODY_TYPE PLUMBING
J 0
(-6795 3982);
DISPLAY 0.340426 (-6795 3982);
PAINT GREEN (-6795 3982);
DISPLAY INVISIBLE (-6795 3982);
FORCEPROP 1 LAST HDL_POWER GND
J 0
(-6750 4175);
DISPLAY 1.170213 (-6750 4175);
PAINT GREEN (-6750 4175);
DISPLAY INVISIBLE (-6750 4175);
FORCEADD RES..1
(-6350 2075);
FORCEPROP 1 LAST MATERIAL CHIP
J 0
(-6350 1925);
DISPLAY 0.617021 (-6350 1925);
PAINT SKYBLUE (-6350 1925);
FORCEPROP 1 LAST LOCATION R1C21
J 0
(-6400 2125);
DISPLAY 0.617021 (-6400 2125);
PAINT AQUA (-6400 2125);
FORCEPROP 1 LAST PART_NUMBER G21796-066
J 0
(-6400 2175);
DISPLAY 0.617021 (-6400 2175);
PAINT BLUE (-6400 2175);
FORCEPROP 1 LAST VALUE 10.0
J 2
(-6375 1975);
DISPLAY 0.617021 (-6375 1975);
PAINT SKYBLUE (-6375 1975);
FORCEPROP 1 LAST WATTAGE 1/16W
J 2
(-6375 1925);
DISPLAY 0.617021 (-6375 1925);
PAINT SKYBLUE (-6375 1925);
FORCEPROP 2 LAST NO_XNET_CONNECTION 1
J 0
(-6400 2275);
PAINT MONO (-6400 2275);
FORCEPROP 1 LAST PACK_TYPE 0402
J 0
(-6450 2025);
DISPLAY 0.617021 (-6450 2025);
PAINT SKYBLUE (-6450 2025);
FORCEPROP 1 LASTPIN (-6250 2075) $PN 2
J 0
(-6288 2087);
DISPLAY 0.617021 (-6288 2087);
PAINT WHITE (-6288 2087);
FORCEPROP 1 LAST TOLERANCE 1%
J 0
(-6350 1975);
DISPLAY 0.617021 (-6350 1975);
PAINT SKYBLUE (-6350 1975);
FORCEPROP 1 LASTPIN (-6450 2075) $PN 1
J 0
(-6438 2087);
DISPLAY 0.617021 (-6438 2087);
PAINT WHITE (-6438 2087);
FORCEPROP 2 LAST CDS_LIB mstr_discrete
J 0
(-6350 2075);
PAINT MONO (-6350 2075);
DISPLAY INVISIBLE (-6350 2075);
FORCEPROP 2 LAST SEC_TYPE 0402
J 0
(-6400 2275);
DISPLAY 1.021277 (-6400 2275);
PAINT ORANGE (-6400 2275);
DISPLAY INVISIBLE (-6400 2275);
FORCEPROP 2 LAST SEC 1
J 0
(-6400 2275);
DISPLAY 0.680851 (-6400 2275);
PAINT MONO (-6400 2275);
DISPLAY INVISIBLE (-6400 2275);
FORCEPROP 2 LAST CDS_LOCATION R1C21
J 0
(-6400 2125);
DISPLAY 0.617021 (-6400 2125);
PAINT AQUA (-6400 2125);
DISPLAY INVISIBLE (-6400 2125);
FORCEPROP 1 LAST PATH I77
J 0
(-6400 2225);
DISPLAY 0.978723 (-6400 2225);
PAINT WHITE (-6400 2225);
DISPLAY INVISIBLE (-6400 2225);
FORCEPROP 2 LAST ROOM PVCCIN_CPU1_VR
J 0
(-6400 2225);
DISPLAY 1.021277 (-6400 2225);
PAINT WHITE (-6400 2225);
DISPLAY INVISIBLE (-6400 2225);
FORCEADD CAP..1
(-6550 2375);
FORCEPROP 1 LAST PART_NUMBER A36096-050
J 0
(-6500 2325);
DISPLAY 0.617021 (-6500 2325);
PAINT BLUE (-6500 2325);
FORCEPROP 1 LAST TOLERANCE 10%
J 0
(-6325 2425);
DISPLAY 0.617021 (-6325 2425);
PAINT SKYBLUE (-6325 2425);
FORCEPROP 1 LASTPIN (-6550 2275) $PN 2
J 0
(-6540 2255);
DISPLAY 0.617021 (-6540 2255);
PAINT WHITE (-6540 2255);
FORCEPROP 1 LAST PACK_TYPE 0402LF
J 0
(-6500 2275);
DISPLAY 0.617021 (-6500 2275);
PAINT SKYBLUE (-6500 2275);
FORCEPROP 2 LAST NO_XNET_CONNECTION 1
J 0
(-6500 2575);
PAINT MONO (-6500 2575);
FORCEPROP 1 LAST VALUE 220PF
J 0
(-6500 2425);
DISPLAY 0.617021 (-6500 2425);
PAINT SKYBLUE (-6500 2425);
FORCEPROP 1 LAST LOCATION C1D1
J 0
(-6500 2475);
DISPLAY 0.617021 (-6500 2475);
PAINT AQUA (-6500 2475);
FORCEPROP 1 LASTPIN (-6550 2475) $PN 1
J 0
(-6540 2455);
DISPLAY 0.617021 (-6540 2455);
PAINT WHITE (-6540 2455);
FORCEPROP 1 LAST VOLTAGE 50V
J 0
(-6500 2375);
DISPLAY 0.617021 (-6500 2375);
PAINT SKYBLUE (-6500 2375);
FORCEPROP 1 LAST MATERIAL X7R
J 0
(-6375 2375);
DISPLAY 0.617021 (-6375 2375);
PAINT SKYBLUE (-6375 2375);
FORCEPROP 2 LAST SEC_TYPE 0402LF
J 0
(-6500 2575);
DISPLAY 1.021277 (-6500 2575);
PAINT ORANGE (-6500 2575);
DISPLAY INVISIBLE (-6500 2575);
FORCEPROP 2 LAST SEC 1
J 0
(-6500 2575);
DISPLAY 0.680851 (-6500 2575);
PAINT MONO (-6500 2575);
DISPLAY INVISIBLE (-6500 2575);
FORCEPROP 1 LAST PATH I78
J 0
(-6500 2525);
DISPLAY 0.978723 (-6500 2525);
PAINT WHITE (-6500 2525);
DISPLAY INVISIBLE (-6500 2525);
FORCEPROP 2 LAST ROOM PVCCIN_CPU1_VR
J 0
(-6500 2525);
DISPLAY 1.361702 (-6500 2525);
PAINT WHITE (-6500 2525);
DISPLAY INVISIBLE (-6500 2525);
FORCEPROP 2 LAST CDS_LOCATION C1D1
J 0
(-6500 2475);
DISPLAY 0.617021 (-6500 2475);
PAINT AQUA (-6500 2475);
DISPLAY INVISIBLE (-6500 2475);
FORCEPROP 2 LAST CDS_LIB mstr_discrete
J 0
(-6550 2375);
PAINT ORANGE (-6550 2375);
DISPLAY INVISIBLE (-6550 2375);
FORCEADD RES..1
(-6775 2575);
FORCEPROP 1 LAST PART_NUMBER G21796-066
J 0
(-6825 2675);
DISPLAY 0.617021 (-6825 2675);
PAINT BLUE (-6825 2675);
FORCEPROP 1 LAST WATTAGE 1/16W
J 2
(-6800 2425);
DISPLAY 0.617021 (-6800 2425);
PAINT SKYBLUE (-6800 2425);
FORCEPROP 1 LAST PACK_TYPE 0402
J 0
(-6850 2525);
DISPLAY 0.617021 (-6850 2525);
PAINT SKYBLUE (-6850 2525);
FORCEPROP 1 LAST TOLERANCE 1%
J 0
(-6775 2475);
DISPLAY 0.617021 (-6775 2475);
PAINT SKYBLUE (-6775 2475);
FORCEPROP 2 LAST NO_XNET_CONNECTION 1
J 0
(-6825 2775);
PAINT MONO (-6825 2775);
FORCEPROP 1 LAST VALUE 10.0
J 2
(-6800 2475);
DISPLAY 0.617021 (-6800 2475);
PAINT SKYBLUE (-6800 2475);
FORCEPROP 1 LASTPIN (-6875 2575) $PN 1
J 0
(-6863 2587);
DISPLAY 0.617021 (-6863 2587);
PAINT WHITE (-6863 2587);
FORCEPROP 1 LAST MATERIAL CHIP
J 0
(-6775 2425);
DISPLAY 0.617021 (-6775 2425);
PAINT SKYBLUE (-6775 2425);
FORCEPROP 1 LASTPIN (-6675 2575) $PN 2
J 0
(-6713 2587);
DISPLAY 0.617021 (-6713 2587);
PAINT WHITE (-6713 2587);
FORCEPROP 1 LAST LOCATION R1D4
J 0
(-6825 2625);
DISPLAY 0.617021 (-6825 2625);
PAINT AQUA (-6825 2625);
FORCEPROP 2 LAST SEC_TYPE 0402
J 0
(-6825 2775);
DISPLAY 1.021277 (-6825 2775);
PAINT ORANGE (-6825 2775);
DISPLAY INVISIBLE (-6825 2775);
FORCEPROP 2 LAST CDS_LIB mstr_discrete
J 0
(-6775 2575);
PAINT MONO (-6775 2575);
DISPLAY INVISIBLE (-6775 2575);
FORCEPROP 2 LAST ROOM PVCCIN_CPU1_VR
J 0
(-6825 2725);
DISPLAY 1.021277 (-6825 2725);
PAINT WHITE (-6825 2725);
DISPLAY INVISIBLE (-6825 2725);
FORCEPROP 1 LAST PATH I79
J 0
(-6825 2725);
DISPLAY 0.978723 (-6825 2725);
PAINT WHITE (-6825 2725);
DISPLAY INVISIBLE (-6825 2725);
FORCEPROP 2 LAST CDS_LOCATION R1D4
J 0
(-6825 2625);
DISPLAY 0.617021 (-6825 2625);
PAINT AQUA (-6825 2625);
DISPLAY INVISIBLE (-6825 2625);
FORCEPROP 2 LAST SEC 1
J 0
(-6825 2775);
DISPLAY 0.680851 (-6825 2775);
PAINT MONO (-6825 2775);
DISPLAY INVISIBLE (-6825 2775);
FORCEADD OFFPAGE..2
(-1150 3025);
FORCEPROP 2 LAST $XR1 145 
J 0
(-871 3025);
DISPLAY 0.638298 (-871 3025);
PAINT MONO (-871 3025);
FORCEPROP 2 LAST $XR0 95 
J 0
(-961 3025);
DISPLAY 0.638298 (-961 3025);
PAINT MONO (-961 3025);
FORCEPROP 1 LAST COMMENT_BODY TRUE
J 0
(-1195 2930);
DISPLAY 1.170213 (-1195 2930);
PAINT PEACH (-1195 2930);
DISPLAY INVISIBLE (-1195 2930);
FORCEPROP 1 LAST OFFPAGE TRUE
J 0
(-825 2900);
DISPLAY 1.170213 (-825 2900);
PAINT GREEN (-825 2900);
DISPLAY INVISIBLE (-825 2900);
FORCEPROP 2 LAST PATH I8
J 0
(-975 3100);
DISPLAY 1.021277 (-975 3100);
PAINT ORANGE (-975 3100);
DISPLAY INVISIBLE (-975 3100);
FORCEPROP 2 LAST ROOM PVCCIN_CPU1_VR
J 0
(-1575 3100);
DISPLAY 1.361702 (-1575 3100);
PAINT WHITE (-1575 3100);
DISPLAY INVISIBLE (-1575 3100);
FORCEPROP 2 LAST CDS_LIB mstr_standard
J 0
(-1150 3025);
PAINT ORANGE (-1150 3025);
DISPLAY INVISIBLE (-1150 3025);
FORCEADD OFFPAGE..1
(-7500 3900);
FORCEPROP 2 LAST $XR2 213 
J 0
(-7961 3900);
DISPLAY 0.638298 (-7961 3900);
PAINT MONO (-7961 3900);
FORCEPROP 2 LAST $XR1 193 
J 0
(-7841 3900);
DISPLAY 0.638298 (-7841 3900);
PAINT MONO (-7841 3900);
FORCEPROP 2 LAST $XR0 55 
J 0
(-7721 3900);
DISPLAY 0.638298 (-7721 3900);
PAINT MONO (-7721 3900);
FORCEPROP 1 LAST COMMENT_BODY TRUE
J 0
(-7375 3800);
DISPLAY 1.170213 (-7375 3800);
PAINT PEACH (-7375 3800);
DISPLAY INVISIBLE (-7375 3800);
FORCEPROP 1 LAST OFFPAGE TRUE
J 0
(-7175 3775);
DISPLAY 1.170213 (-7175 3775);
PAINT GREEN (-7175 3775);
DISPLAY INVISIBLE (-7175 3775);
FORCEPROP 2 LAST CDS_LIB mstr_standard
J 0
(-7500 3900);
PAINT ORANGE (-7500 3900);
DISPLAY INVISIBLE (-7500 3900);
FORCEPROP 2 LAST PATH I80
J 0
(-7450 3975);
DISPLAY 1.021277 (-7450 3975);
PAINT ORANGE (-7450 3975);
DISPLAY INVISIBLE (-7450 3975);
FORCEPROP 2 LAST ROOM PVCCIN_CPU1_VR
J 0
(-8050 3975);
DISPLAY 1.361702 (-8050 3975);
PAINT WHITE (-8050 3975);
DISPLAY INVISIBLE (-8050 3975);
FORCEADD OFFPAGE..1
(-7500 3225);
FORCEPROP 2 LAST $XR0 207 
J 0
(-7752 3225);
DISPLAY 0.638298 (-7752 3225);
PAINT MONO (-7752 3225);
FORCEPROP 1 LAST COMMENT_BODY TRUE
J 0
(-7375 3125);
DISPLAY 1.170213 (-7375 3125);
PAINT PEACH (-7375 3125);
DISPLAY INVISIBLE (-7375 3125);
FORCEPROP 1 LAST OFFPAGE TRUE
J 0
(-7175 3100);
DISPLAY 1.170213 (-7175 3100);
PAINT GREEN (-7175 3100);
DISPLAY INVISIBLE (-7175 3100);
FORCEPROP 2 LAST CDS_LIB mstr_standard
J 0
(-7500 3225);
PAINT ORANGE (-7500 3225);
DISPLAY INVISIBLE (-7500 3225);
FORCEPROP 2 LAST ROOM PVCCIN_CPU1_VR
J 0
(-8050 3300);
DISPLAY 1.361702 (-8050 3300);
PAINT WHITE (-8050 3300);
DISPLAY INVISIBLE (-8050 3300);
FORCEPROP 2 LAST PATH I81
J 0
(-7750 3275);
DISPLAY 1.021277 (-7750 3275);
PAINT ORANGE (-7750 3275);
DISPLAY INVISIBLE (-7750 3275);
FORCEADD OFFPAGE..1
(-7500 3175);
FORCEPROP 2 LAST $XR0 207 
J 0
(-7752 3175);
DISPLAY 0.638298 (-7752 3175);
PAINT MONO (-7752 3175);
FORCEPROP 1 LAST COMMENT_BODY TRUE
J 0
(-7375 3075);
DISPLAY 1.170213 (-7375 3075);
PAINT PEACH (-7375 3075);
DISPLAY INVISIBLE (-7375 3075);
FORCEPROP 1 LAST OFFPAGE TRUE
J 0
(-7175 3050);
DISPLAY 1.170213 (-7175 3050);
PAINT GREEN (-7175 3050);
DISPLAY INVISIBLE (-7175 3050);
FORCEPROP 2 LAST CDS_LIB mstr_standard
J 0
(-7500 3175);
PAINT ORANGE (-7500 3175);
DISPLAY INVISIBLE (-7500 3175);
FORCEPROP 2 LAST ROOM PVCCIN_CPU1_VR
J 0
(-8050 3250);
DISPLAY 1.361702 (-8050 3250);
PAINT WHITE (-8050 3250);
DISPLAY INVISIBLE (-8050 3250);
FORCEPROP 2 LAST PATH I82
J 0
(-7750 3225);
DISPLAY 1.021277 (-7750 3225);
PAINT ORANGE (-7750 3225);
DISPLAY INVISIBLE (-7750 3225);
FORCEADD OFFPAGE..1
(-7500 3125);
FORCEPROP 2 LAST $XR0 208 
J 0
(-7752 3125);
DISPLAY 0.638298 (-7752 3125);
PAINT MONO (-7752 3125);
FORCEPROP 1 LAST COMMENT_BODY TRUE
J 0
(-7375 3025);
DISPLAY 1.170213 (-7375 3025);
PAINT PEACH (-7375 3025);
DISPLAY INVISIBLE (-7375 3025);
FORCEPROP 1 LAST OFFPAGE TRUE
J 0
(-7175 3000);
DISPLAY 1.170213 (-7175 3000);
PAINT GREEN (-7175 3000);
DISPLAY INVISIBLE (-7175 3000);
FORCEPROP 2 LAST CDS_LIB mstr_standard
J 0
(-7500 3125);
PAINT ORANGE (-7500 3125);
DISPLAY INVISIBLE (-7500 3125);
FORCEPROP 2 LAST ROOM PVCCIN_CPU1_VR
J 0
(-8050 3200);
DISPLAY 1.361702 (-8050 3200);
PAINT WHITE (-8050 3200);
DISPLAY INVISIBLE (-8050 3200);
FORCEPROP 2 LAST PATH I83
J 0
(-7750 3175);
DISPLAY 1.021277 (-7750 3175);
PAINT ORANGE (-7750 3175);
DISPLAY INVISIBLE (-7750 3175);
FORCEADD OFFPAGE..1
(-7500 2925);
FORCEPROP 2 LAST $XR0 207 
J 0
(-7752 2925);
DISPLAY 0.638298 (-7752 2925);
PAINT MONO (-7752 2925);
FORCEPROP 1 LAST COMMENT_BODY TRUE
J 0
(-7375 2825);
DISPLAY 1.170213 (-7375 2825);
PAINT PEACH (-7375 2825);
DISPLAY INVISIBLE (-7375 2825);
FORCEPROP 1 LAST OFFPAGE TRUE
J 0
(-7175 2800);
DISPLAY 1.170213 (-7175 2800);
PAINT GREEN (-7175 2800);
DISPLAY INVISIBLE (-7175 2800);
FORCEPROP 2 LAST CDS_LIB mstr_standard
J 0
(-7500 2925);
PAINT ORANGE (-7500 2925);
DISPLAY INVISIBLE (-7500 2925);
FORCEPROP 2 LAST ROOM PVCCIN_CPU1_VR
J 0
(-8050 3000);
DISPLAY 1.361702 (-8050 3000);
PAINT WHITE (-8050 3000);
DISPLAY INVISIBLE (-8050 3000);
FORCEPROP 2 LAST PATH I84
J 0
(-7750 2975);
DISPLAY 1.021277 (-7750 2975);
PAINT ORANGE (-7750 2975);
DISPLAY INVISIBLE (-7750 2975);
FORCEADD OFFPAGE..1
(-7500 3025);
FORCEPROP 2 LAST $XR0 209 
J 0
(-7752 3025);
DISPLAY 0.638298 (-7752 3025);
PAINT MONO (-7752 3025);
FORCEPROP 1 LAST COMMENT_BODY TRUE
J 0
(-7375 2925);
DISPLAY 1.170213 (-7375 2925);
PAINT PEACH (-7375 2925);
DISPLAY INVISIBLE (-7375 2925);
FORCEPROP 1 LAST OFFPAGE TRUE
J 0
(-7175 2900);
DISPLAY 1.170213 (-7175 2900);
PAINT GREEN (-7175 2900);
DISPLAY INVISIBLE (-7175 2900);
FORCEPROP 2 LAST PATH I85
J 0
(-7450 3100);
DISPLAY 1.021277 (-7450 3100);
PAINT ORANGE (-7450 3100);
DISPLAY INVISIBLE (-7450 3100);
FORCEPROP 2 LAST ROOM PVCCIN_CPU1_VR
J 0
(-8050 3100);
DISPLAY 1.361702 (-8050 3100);
PAINT WHITE (-8050 3100);
DISPLAY INVISIBLE (-8050 3100);
FORCEPROP 2 LAST CDS_LIB mstr_standard
J 0
(-7500 3025);
PAINT ORANGE (-7500 3025);
DISPLAY INVISIBLE (-7500 3025);
FORCEADD OFFPAGE..1
(-7500 3075);
FORCEPROP 2 LAST $XR0 208 
J 0
(-7752 3075);
DISPLAY 0.638298 (-7752 3075);
PAINT MONO (-7752 3075);
FORCEPROP 1 LAST COMMENT_BODY TRUE
J 0
(-7375 2975);
DISPLAY 1.170213 (-7375 2975);
PAINT PEACH (-7375 2975);
DISPLAY INVISIBLE (-7375 2975);
FORCEPROP 1 LAST OFFPAGE TRUE
J 0
(-7175 2950);
DISPLAY 1.170213 (-7175 2950);
PAINT GREEN (-7175 2950);
DISPLAY INVISIBLE (-7175 2950);
FORCEPROP 2 LAST CDS_LIB mstr_standard
J 0
(-7500 3075);
PAINT ORANGE (-7500 3075);
DISPLAY INVISIBLE (-7500 3075);
FORCEPROP 2 LAST ROOM PVCCIN_CPU1_VR
J 0
(-8050 3150);
DISPLAY 1.361702 (-8050 3150);
PAINT WHITE (-8050 3150);
DISPLAY INVISIBLE (-8050 3150);
FORCEPROP 2 LAST PATH I86
J 0
(-7750 3125);
DISPLAY 1.021277 (-7750 3125);
PAINT ORANGE (-7750 3125);
DISPLAY INVISIBLE (-7750 3125);
FORCEADD OFFPAGE..1
(-7500 2875);
FORCEPROP 2 LAST $XR0 207 
J 0
(-7752 2875);
DISPLAY 0.638298 (-7752 2875);
PAINT MONO (-7752 2875);
FORCEPROP 1 LAST COMMENT_BODY TRUE
J 0
(-7375 2775);
DISPLAY 1.170213 (-7375 2775);
PAINT PEACH (-7375 2775);
DISPLAY INVISIBLE (-7375 2775);
FORCEPROP 1 LAST OFFPAGE TRUE
J 0
(-7175 2750);
DISPLAY 1.170213 (-7175 2750);
PAINT GREEN (-7175 2750);
DISPLAY INVISIBLE (-7175 2750);
FORCEPROP 2 LAST CDS_LIB mstr_standard
J 0
(-7500 2875);
PAINT ORANGE (-7500 2875);
DISPLAY INVISIBLE (-7500 2875);
FORCEPROP 2 LAST ROOM PVCCIN_CPU1_VR
J 0
(-8050 2950);
DISPLAY 1.361702 (-8050 2950);
PAINT WHITE (-8050 2950);
DISPLAY INVISIBLE (-8050 2950);
FORCEPROP 2 LAST PATH I87
J 0
(-7750 2925);
DISPLAY 1.021277 (-7750 2925);
PAINT ORANGE (-7750 2925);
DISPLAY INVISIBLE (-7750 2925);
FORCEADD OFFPAGE..1
(-7500 2825);
FORCEPROP 2 LAST $XR0 208 
J 0
(-7752 2825);
DISPLAY 0.638298 (-7752 2825);
PAINT MONO (-7752 2825);
FORCEPROP 1 LAST COMMENT_BODY TRUE
J 0
(-7375 2725);
DISPLAY 1.170213 (-7375 2725);
PAINT PEACH (-7375 2725);
DISPLAY INVISIBLE (-7375 2725);
FORCEPROP 1 LAST OFFPAGE TRUE
J 0
(-7175 2700);
DISPLAY 0.936170 (-7175 2700);
PAINT GREEN (-7175 2700);
DISPLAY INVISIBLE (-7175 2700);
FORCEPROP 2 LAST CDS_LIB mstr_standard
J 0
(-7500 2825);
PAINT ORANGE (-7500 2825);
DISPLAY INVISIBLE (-7500 2825);
FORCEPROP 2 LAST ROOM PVCCIN_CPU1_VR
J 0
(-8050 2900);
DISPLAY 1.361702 (-8050 2900);
PAINT WHITE (-8050 2900);
DISPLAY INVISIBLE (-8050 2900);
FORCEPROP 2 LAST PATH I88
J 0
(-7750 2875);
DISPLAY 1.021277 (-7750 2875);
PAINT ORANGE (-7750 2875);
DISPLAY INVISIBLE (-7750 2875);
FORCEADD OFFPAGE..1
(-7500 2775);
FORCEPROP 2 LAST $XR0 208 
J 0
(-7752 2775);
DISPLAY 0.638298 (-7752 2775);
PAINT MONO (-7752 2775);
FORCEPROP 1 LAST COMMENT_BODY TRUE
J 0
(-7375 2675);
DISPLAY 1.170213 (-7375 2675);
PAINT PEACH (-7375 2675);
DISPLAY INVISIBLE (-7375 2675);
FORCEPROP 1 LAST OFFPAGE TRUE
J 0
(-7175 2650);
DISPLAY 1.170213 (-7175 2650);
PAINT GREEN (-7175 2650);
DISPLAY INVISIBLE (-7175 2650);
FORCEPROP 2 LAST CDS_LIB mstr_standard
J 0
(-7500 2775);
PAINT ORANGE (-7500 2775);
DISPLAY INVISIBLE (-7500 2775);
FORCEPROP 2 LAST ROOM PVCCIN_CPU1_VR
J 0
(-8050 2850);
DISPLAY 1.361702 (-8050 2850);
PAINT WHITE (-8050 2850);
DISPLAY INVISIBLE (-8050 2850);
FORCEPROP 2 LAST PATH I89
J 0
(-7750 2825);
DISPLAY 1.021277 (-7750 2825);
PAINT ORANGE (-7750 2825);
DISPLAY INVISIBLE (-7750 2825);
FORCEADD OFFPAGE..2
(-1150 2925);
FORCEPROP 2 LAST $XR2 55 
J 0
(-721 2925);
DISPLAY 0.638298 (-721 2925);
PAINT MONO (-721 2925);
FORCEPROP 2 LAST $XR1 213 
J 0
(-841 2925);
DISPLAY 0.638298 (-841 2925);
PAINT MONO (-841 2925);
FORCEPROP 2 LAST $XR0 193 
J 0
(-961 2925);
DISPLAY 0.638298 (-961 2925);
PAINT MONO (-961 2925);
FORCEPROP 1 LAST COMMENT_BODY TRUE
J 0
(-1195 2830);
DISPLAY 1.170213 (-1195 2830);
PAINT PEACH (-1195 2830);
DISPLAY INVISIBLE (-1195 2830);
FORCEPROP 1 LAST OFFPAGE TRUE
J 0
(-825 2800);
DISPLAY 1.170213 (-825 2800);
PAINT GREEN (-825 2800);
DISPLAY INVISIBLE (-825 2800);
FORCEPROP 2 LAST PATH I9
J 0
(-975 3000);
DISPLAY 1.021277 (-975 3000);
PAINT ORANGE (-975 3000);
DISPLAY INVISIBLE (-975 3000);
FORCEPROP 2 LAST CDS_LIB mstr_standard
J 0
(-1150 2925);
PAINT ORANGE (-1150 2925);
DISPLAY INVISIBLE (-1150 2925);
FORCEPROP 2 LAST ROOM PVCCIN_CPU1_VR
J 0
(-1575 3000);
DISPLAY 1.361702 (-1575 3000);
PAINT WHITE (-1575 3000);
DISPLAY INVISIBLE (-1575 3000);
FORCEADD OFFPAGE..1
(-7500 2725);
FORCEPROP 2 LAST $XR0 209 
J 0
(-7752 2725);
DISPLAY 0.638298 (-7752 2725);
PAINT MONO (-7752 2725);
FORCEPROP 1 LAST COMMENT_BODY TRUE
J 0
(-7375 2625);
DISPLAY 1.170213 (-7375 2625);
PAINT PEACH (-7375 2625);
DISPLAY INVISIBLE (-7375 2625);
FORCEPROP 1 LAST OFFPAGE TRUE
J 0
(-7175 2600);
DISPLAY 1.170213 (-7175 2600);
PAINT GREEN (-7175 2600);
DISPLAY INVISIBLE (-7175 2600);
FORCEPROP 2 LAST PATH I90
J 0
(-7450 2800);
DISPLAY 1.021277 (-7450 2800);
PAINT ORANGE (-7450 2800);
DISPLAY INVISIBLE (-7450 2800);
FORCEPROP 2 LAST CDS_LIB mstr_standard
J 0
(-7500 2725);
PAINT ORANGE (-7500 2725);
DISPLAY INVISIBLE (-7500 2725);
FORCEPROP 2 LAST ROOM PVCCIN_CPU1_VR
J 0
(-8050 2800);
DISPLAY 1.361702 (-8050 2800);
PAINT WHITE (-8050 2800);
DISPLAY INVISIBLE (-8050 2800);
FORCEADD OFFPAGE..1
(-7500 2575);
FORCEPROP 2 LAST $XR0 209 
J 0
(-7752 2575);
DISPLAY 0.638298 (-7752 2575);
PAINT MONO (-7752 2575);
FORCEPROP 1 LAST COMMENT_BODY TRUE
J 0
(-7375 2475);
DISPLAY 1.170213 (-7375 2475);
PAINT PEACH (-7375 2475);
DISPLAY INVISIBLE (-7375 2475);
FORCEPROP 1 LAST OFFPAGE TRUE
J 0
(-7175 2450);
DISPLAY 1.170213 (-7175 2450);
PAINT GREEN (-7175 2450);
DISPLAY INVISIBLE (-7175 2450);
FORCEPROP 2 LAST CDS_LIB mstr_standard
J 0
(-7500 2575);
PAINT ORANGE (-7500 2575);
DISPLAY INVISIBLE (-7500 2575);
FORCEPROP 2 LAST ROOM PVCCIN_CPU1_VR
J 0
(-8050 2650);
DISPLAY 1.361702 (-8050 2650);
PAINT WHITE (-8050 2650);
DISPLAY INVISIBLE (-8050 2650);
FORCEPROP 2 LAST PATH I91
J 0
(-7700 2625);
DISPLAY 1.021277 (-7700 2625);
PAINT ORANGE (-7700 2625);
DISPLAY INVISIBLE (-7700 2625);
FORCEADD OFFPAGE..1
(-7500 2250);
FORCEPROP 2 LAST $XR0 209 
J 0
(-7752 2250);
DISPLAY 0.638298 (-7752 2250);
PAINT MONO (-7752 2250);
FORCEPROP 1 LAST COMMENT_BODY TRUE
J 0
(-7375 2150);
DISPLAY 1.170213 (-7375 2150);
PAINT PEACH (-7375 2150);
DISPLAY INVISIBLE (-7375 2150);
FORCEPROP 1 LAST OFFPAGE TRUE
J 0
(-7175 2125);
DISPLAY 1.170213 (-7175 2125);
PAINT GREEN (-7175 2125);
DISPLAY INVISIBLE (-7175 2125);
FORCEPROP 2 LAST CDS_LIB mstr_standard
J 0
(-7500 2250);
PAINT ORANGE (-7500 2250);
DISPLAY INVISIBLE (-7500 2250);
FORCEPROP 2 LAST ROOM PVCCIN_CPU1_VR
J 0
(-8050 2325);
DISPLAY 1.361702 (-8050 2325);
PAINT WHITE (-8050 2325);
DISPLAY INVISIBLE (-8050 2325);
FORCEPROP 2 LAST PATH I92
J 0
(-7700 2300);
DISPLAY 1.021277 (-7700 2300);
PAINT ORANGE (-7700 2300);
DISPLAY INVISIBLE (-7700 2300);
FORCEADD OFFPAGE..1
(-7500 2075);
FORCEPROP 2 LAST $XR0 210 
J 0
(-7752 2075);
DISPLAY 0.638298 (-7752 2075);
PAINT MONO (-7752 2075);
FORCEPROP 1 LAST COMMENT_BODY TRUE
J 0
(-7375 1975);
DISPLAY 1.170213 (-7375 1975);
PAINT PEACH (-7375 1975);
DISPLAY INVISIBLE (-7375 1975);
FORCEPROP 1 LAST OFFPAGE TRUE
J 0
(-7175 1950);
DISPLAY 1.170213 (-7175 1950);
PAINT GREEN (-7175 1950);
DISPLAY INVISIBLE (-7175 1950);
FORCEPROP 2 LAST PATH I94
J 0
(-7450 2150);
DISPLAY 1.021277 (-7450 2150);
PAINT ORANGE (-7450 2150);
DISPLAY INVISIBLE (-7450 2150);
FORCEPROP 2 LAST CDS_LIB mstr_standard
J 0
(-7500 2075);
PAINT ORANGE (-7500 2075);
DISPLAY INVISIBLE (-7500 2075);
FORCEPROP 2 LAST ROOM PVCCIN_CPU1_VR
J 0
(-8050 2150);
DISPLAY 1.361702 (-8050 2150);
PAINT WHITE (-8050 2150);
DISPLAY INVISIBLE (-8050 2150);
FORCEADD OFFPAGE..1
(-7500 1825);
FORCEPROP 2 LAST $XR0 191 
J 0
(-7752 1825);
DISPLAY 0.638298 (-7752 1825);
PAINT MONO (-7752 1825);
FORCEPROP 1 LAST COMMENT_BODY TRUE
J 0
(-7375 1725);
DISPLAY 1.170213 (-7375 1725);
PAINT PEACH (-7375 1725);
DISPLAY INVISIBLE (-7375 1725);
FORCEPROP 1 LAST OFFPAGE TRUE
J 0
(-7175 1700);
DISPLAY 1.170213 (-7175 1700);
PAINT GREEN (-7175 1700);
DISPLAY INVISIBLE (-7175 1700);
FORCEPROP 2 LAST PATH I95
J 0
(-7450 1900);
DISPLAY 1.021277 (-7450 1900);
PAINT ORANGE (-7450 1900);
DISPLAY INVISIBLE (-7450 1900);
FORCEPROP 2 LAST CDS_LIB mstr_standard
J 0
(-7500 1825);
PAINT ORANGE (-7500 1825);
DISPLAY INVISIBLE (-7500 1825);
FORCEPROP 2 LAST ROOM PVCCIN_CPU1_VR
J 0
(-8050 1900);
DISPLAY 1.361702 (-8050 1900);
PAINT WHITE (-8050 1900);
DISPLAY INVISIBLE (-8050 1900);
FORCEADD OFFPAGE..1
(-7500 1875);
FORCEPROP 2 LAST $XR2 209 
J 0
(-7992 1875);
DISPLAY 0.638298 (-7992 1875);
PAINT MONO (-7992 1875);
FORCEPROP 2 LAST $XR1 208 
J 0
(-7872 1875);
DISPLAY 0.638298 (-7872 1875);
PAINT MONO (-7872 1875);
FORCEPROP 2 LAST $XR0 207 
J 0
(-7752 1875);
DISPLAY 0.638298 (-7752 1875);
PAINT MONO (-7752 1875);
FORCEPROP 1 LAST COMMENT_BODY TRUE
J 0
(-7375 1775);
DISPLAY 1.170213 (-7375 1775);
PAINT PEACH (-7375 1775);
DISPLAY INVISIBLE (-7375 1775);
FORCEPROP 1 LAST OFFPAGE TRUE
J 0
(-7175 1750);
DISPLAY 1.170213 (-7175 1750);
PAINT GREEN (-7175 1750);
DISPLAY INVISIBLE (-7175 1750);
FORCEPROP 2 LAST CDS_LIB mstr_standard
J 0
(-7500 1875);
PAINT ORANGE (-7500 1875);
DISPLAY INVISIBLE (-7500 1875);
FORCEPROP 2 LAST ROOM PVCCIN_CPU1_VR
J 0
(-8050 1950);
DISPLAY 1.361702 (-8050 1950);
PAINT WHITE (-8050 1950);
DISPLAY INVISIBLE (-8050 1950);
FORCEPROP 2 LAST PATH I96
J 0
(-7750 1925);
DISPLAY 1.021277 (-7750 1925);
PAINT ORANGE (-7750 1925);
DISPLAY INVISIBLE (-7750 1925);
FORCEADD OFFPAGE..1
(-7500 1925);
FORCEPROP 2 LAST $XR0 210 
J 0
(-7752 1925);
DISPLAY 0.638298 (-7752 1925);
PAINT MONO (-7752 1925);
FORCEPROP 1 LAST COMMENT_BODY TRUE
J 0
(-7375 1825);
DISPLAY 1.170213 (-7375 1825);
PAINT PEACH (-7375 1825);
DISPLAY INVISIBLE (-7375 1825);
FORCEPROP 1 LAST OFFPAGE TRUE
J 0
(-7175 1800);
DISPLAY 1.170213 (-7175 1800);
PAINT GREEN (-7175 1800);
DISPLAY INVISIBLE (-7175 1800);
FORCEPROP 2 LAST ROOM PVCCIN_CPU1_VR
J 0
(-8050 2000);
DISPLAY 1.361702 (-8050 2000);
PAINT WHITE (-8050 2000);
DISPLAY INVISIBLE (-8050 2000);
FORCEPROP 2 LAST CDS_LIB mstr_standard
J 0
(-7500 1925);
PAINT ORANGE (-7500 1925);
DISPLAY INVISIBLE (-7500 1925);
FORCEPROP 2 LAST PATH I97
J 0
(-7450 2000);
DISPLAY 1.021277 (-7450 2000);
PAINT ORANGE (-7450 2000);
DISPLAY INVISIBLE (-7450 2000);
FORCEADD OFFPAGE..1
(-7500 1575);
FORCEPROP 2 LAST $XR0 210 
J 0
(-7752 1575);
DISPLAY 0.638298 (-7752 1575);
PAINT MONO (-7752 1575);
FORCEPROP 1 LAST COMMENT_BODY TRUE
J 0
(-7375 1475);
DISPLAY 1.170213 (-7375 1475);
PAINT PEACH (-7375 1475);
DISPLAY INVISIBLE (-7375 1475);
FORCEPROP 1 LAST OFFPAGE TRUE
J 0
(-7175 1450);
DISPLAY 1.170213 (-7175 1450);
PAINT GREEN (-7175 1450);
DISPLAY INVISIBLE (-7175 1450);
FORCEPROP 2 LAST PATH I98
J 0
(-7450 1650);
DISPLAY 1.021277 (-7450 1650);
PAINT ORANGE (-7450 1650);
DISPLAY INVISIBLE (-7450 1650);
FORCEPROP 2 LAST CDS_LIB mstr_standard
J 0
(-7500 1575);
PAINT ORANGE (-7500 1575);
DISPLAY INVISIBLE (-7500 1575);
FORCEPROP 2 LAST ROOM PVCCIN_CPU1_VR
J 0
(-8050 1650);
DISPLAY 1.361702 (-8050 1650);
PAINT WHITE (-8050 1650);
DISPLAY INVISIBLE (-8050 1650);
FORCEADD OFFPAGE..1
(-7500 1725);
FORCEPROP 2 LAST $XR0 206 
J 0
(-7752 1725);
DISPLAY 0.638298 (-7752 1725);
PAINT MONO (-7752 1725);
FORCEPROP 2 LAST ROOM PVCCIN_CPU1_VR
J 0
(-8050 1800);
DISPLAY 1.361702 (-8050 1800);
PAINT WHITE (-8050 1800);
DISPLAY INVISIBLE (-8050 1800);
FORCEPROP 1 LAST OFFPAGE TRUE
J 0
(-7175 1600);
DISPLAY 1.170213 (-7175 1600);
PAINT GREEN (-7175 1600);
DISPLAY INVISIBLE (-7175 1600);
FORCEPROP 1 LAST COMMENT_BODY TRUE
J 0
(-7375 1625);
DISPLAY 1.170213 (-7375 1625);
PAINT PEACH (-7375 1625);
DISPLAY INVISIBLE (-7375 1625);
FORCEPROP 2 LAST PATH I99
J 0
(-7750 1775);
DISPLAY 1.021277 (-7750 1775);
PAINT ORANGE (-7750 1775);
DISPLAY INVISIBLE (-7750 1775);
FORCEPROP 2 LAST CDS_LIB mstr_standard
J 0
(-7500 1725);
PAINT ORANGE (-7500 1725);
DISPLAY INVISIBLE (-7500 1725);
FORCEADD DNS..2
(-2220 3745);
PAINT RED (-2220 3745);
FORCEPROP 1 LAST COMMENT_BODY TRUE
R 1
J 0
(-2145 3520);
DISPLAY 0.872340 (-2145 3520);
PAINT GREEN (-2145 3520);
DISPLAY INVISIBLE (-2145 3520);
FORCEPROP 2 LAST CDS_LIB mstr_misc
J 0
(-2220 3745);
PAINT ORANGE (-2220 3745);
DISPLAY INVISIBLE (-2220 3745);
FORCEADD DESIGN_NOTE..1
(-4175 1350);
FORCEPROP 0 LAST L1 SMBUS ADDRESS: 0XB0
J 0
(-4375 1225);
DISPLAY 1.021277 (-4375 1225);
PAINT VIOLET (-4375 1225);
FORCEPROP 1 LAST COMMENT_BODY TRUE
J 0
(-4150 1450);
DISPLAY 0.978723 (-4150 1450);
PAINT WHITE (-4150 1450);
DISPLAY INVISIBLE (-4150 1450);
FORCEPROP 2 LAST CDS_LIB mstr_symbols
J 0
(-4175 1350);
PAINT WHITE (-4175 1350);
DISPLAY INVISIBLE (-4175 1350);
FORCEADD INTEL_CORP_BPAGE..1
(-100 25);
FORCEPROP 1 LAST CDS_CON_LAST_MODIFIED Fri Jun 16 17:49:15 2017
J 0
(-1525 350);
PAINT ORANGE (-1525 350);
DISPLAY INVISIBLE (-1525 350);
FORCEPROP 1 LAST CUSTOM_TXT_CDS <CURRENT_DESIGN_SHEET> OF <TOTAL_DESIGN_SHEETS>
J 0
(-600 50);
PAINT ORANGE (-600 50);
FORCEPROP 1 LAST CUSTOM_TXT_CDS <CON_LAST_MODIFIED>
J 0
(-4100 125);
PAINT ORANGE (-4100 125);
FORCEPROP 2 LAST CUSTOM_TXT_CDS <XR_PAGE_TITLE>
J 0
(-7990 5275);
DISPLAY 0.638298 (-7990 5275);
PAINT PINK (-7990 5275);
DISPLAY INVISIBLE (-7990 5275);
FORCEPROP 1 LAST SCH_TITLE VCCIN CPU1 (1 OF 4)
J 0
(-8050 75);
DISPLAY 1.212766 (-8050 75);
PAINT YELLOW (-8050 75);
FORCEPROP 1 LAST COMMENT_BODY TRUE
J 0
(-88 37);
DISPLAY 0.468085 (-88 37);
PAINT PEACH (-88 37);
DISPLAY INVISIBLE (-88 37);
FORCEPROP 2 LAST CDS_LIB mstr_symbols
J 0
(-100 25);
PAINT MONO (-100 25);
DISPLAY INVISIBLE (-100 25);
FORCEPROP 2 LAST PAGE_BORDER TRUE
J 0
(-7990 5275);
DISPLAY 0.638298 (-7990 5275);
PAINT PINK (-7990 5275);
DISPLAY INVISIBLE (-7990 5275);
FORCEPROP 2 LAST CDS_XR_PAGE_TITLE CR-206 : @BASEBOARD_FAB2_LIB.BASEBOARD_FAB2(SCH_1):PAGE206
J 0
(-7990 5275);
DISPLAY 0.638298 (-7990 5275);
PAINT PINK (-7990 5275);
DISPLAY INVISIBLE (-7990 5275);
FORCEADD DESIGN_NOTE..1
(-1400 4850);
FORCEPROP 0 LAST L2 PVCCIN_CPU1: 0X00(BUS #1)
J 0
(-1600 4650);
DISPLAY 1.021277 (-1600 4650);
PAINT VIOLET (-1600 4650);
FORCEPROP 0 LAST L1 SVID ADDRESS
J 0
(-1594 4721);
PAINT VIOLET (-1594 4721);
FORCEPROP 0 LAST L3 PVSA_CPU1: 0X01(BUS #1)
J 0
(-1600 4575);
DISPLAY 1.021277 (-1600 4575);
PAINT VIOLET (-1600 4575);
FORCEPROP 1 LAST COMMENT_BODY TRUE
J 0
(-1375 4950);
DISPLAY 1.319149 (-1375 4950);
PAINT WHITE (-1375 4950);
DISPLAY INVISIBLE (-1375 4950);
FORCEPROP 2 LAST CDS_LIB mstr_symbols
J 0
(-1400 4850);
PAINT WHITE (-1400 4850);
DISPLAY INVISIBLE (-1400 4850);
FORCEPROP 2 LAST BOM_COST SM_CONTROLLER
J 0
(-1600 4800);
PAINT WHITE (-1600 4800);
DISPLAY INVISIBLE (-1600 4800);
FORCEPROP 2 LAST ROOM PVCCIN_CPU1_VR
J 0
(-1600 4800);
PAINT WHITE (-1600 4800);
DISPLAY INVISIBLE (-1600 4800);
FORCEADD DNS..2
(-2370 4120);
PAINT RED (-2370 4120);
FORCEPROP 1 LAST COMMENT_BODY TRUE
R 1
J 0
(-2295 3895);
DISPLAY 0.872340 (-2295 3895);
PAINT GREEN (-2295 3895);
DISPLAY INVISIBLE (-2295 3895);
FORCEPROP 2 LAST CDS_LIB mstr_misc
J 0
(-2370 4120);
PAINT ORANGE (-2370 4120);
DISPLAY INVISIBLE (-2370 4120);
WIRE 16 -1 (-1375 3850)(-1375 4100);
WIRE 16 -1 (-4350 4550)(-4350 4375);
WIRE 16 -1 (-3075 4375)(-3075 4525);
WIRE 16 -1 (-3075 4375)(-2875 4375);
WIRE 16 -1 (-3150 4375)(-3075 4375);
WIRE 16 -1 (-3150 4100)(-3150 4375);
WIRE 16 -1 (-2875 4375)(-2725 4375);
WIRE 16 -1 (-2875 4025)(-2875 4375);
WIRE 16 -1 (-2725 4375)(-2375 4375);
WIRE 16 -1 (-2725 4025)(-2725 4375);
WIRE 16 -1 (-2375 4375)(-2225 4375);
WIRE 16 -1 (-2375 4225)(-2375 4375);
WIRE 16 -1 (-2225 4375)(-2050 4375);
WIRE 16 -1 (-2225 3850)(-2225 4375);
WIRE 16 -1 (-2050 4250)(-2050 4375);
WIRE 16 -1 (-1450 2050)(-1450 1975);
WIRE 16 -1 (-1575 725)(-1575 900);
WIRE 16 -1 (-1975 850)(-1975 900);
WIRE 16 -1 (-3650 3775)(-3650 3825);
WIRE 16 -1 (-4050 3775)(-4050 3825);
WIRE 16 -1 (-3175 1600)(-3175 1875);
WIRE 16 -1 (-3175 1875)(-3375 1875);
WIRE 16 -1 (-5225 4700)(-5225 4825);
WIRE 16 -1 (-4650 4700)(-5225 4700);
WIRE 16 -1 (-5225 4700)(-5650 4700);
WIRE 16 -1 (-5650 4550)(-5650 4700);
WIRE 16 -1 (-4650 4500)(-4650 4700);
WIRE 16 -1 (-6150 4675)(-6150 4825);
WIRE 16 -1 (-6150 4025)(-6150 4125);
WIRE 16 -1 (-4500 625)(-4500 825);
WIRE 16 -1 (-4825 575)(-4825 825);
WIRE 16 -1 (-5925 525)(-5925 1175);
WIRE 16 -1 (-6150 525)(-6150 550);
WIRE 16 -1 (-6750 4075)(-6750 4100);
WIRE 16 -1 (-1200 3125)(-2050 3125);
FORCEPROP 2 LAST SIG_NAME FM_PVCCIN_CPU1_PWR_IN_ALERT_N
J 0
(-1905 3147);
DISPLAY 0.617021 (-1905 3147);
PAINT ORANGE (-1905 3147);
WIRE 16 -1 (-2050 3275)(-2050 3125);
WIRE 16 -1 (-2050 4050)(-2050 3275);
WIRE 16 -1 (-3375 3275)(-2050 3275);
WIRE 16 -1 (-3375 2425)(-1200 2425);
FORCEPROP 0 LAST VOLTAGE 3.6
J 0
(-1875 2500);
DISPLAY 1.021277 (-1875 2500);
PAINT SKYBLUE (-1875 2500);
DISPLAY INVISIBLE (-1875 2500);
FORCEPROP 2 LAST SIG_NAME VR_PVCCIN_CPU1_PWM3
J 0
(-1890 2440);
DISPLAY 0.617021 (-1890 2440);
PAINT ORANGE (-1890 2440);
WIRE 3 2175 (-8050 3850)(-7125 3850);
WIRE 3 2175 (-7125 3525)(-7125 3850);
WIRE 3 2175 (-8050 3525)(-8050 3850);
WIRE 3 2175 (-8050 3525)(-7125 3525);
WIRE 16 -1 (-6450 1275)(-6300 1275);
WIRE 16 -1 (-4275 1875)(-5125 1875);
WIRE 16 -1 (-5125 1875)(-5125 1475);
WIRE 16 -1 (-6400 1425)(-6300 1425);
WIRE 16 -1 (-6300 1275)(-6300 1425);
WIRE 16 -1 (-6300 1425)(-6300 1475);
WIRE 16 -1 (-6300 1475)(-5125 1475);
WIRE 16 -1 (-7450 1475)(-6300 1475);
FORCEPROP 2 LAST SIG_NAME ISENSE_PVSA_CPU1_IMON
J 0
(-7440 1490);
DISPLAY 0.617021 (-7440 1490);
PAINT ORANGE (-7440 1490);
WIRE 16 -1 (-6675 1275)(-6600 1275);
WIRE 16 -1 (-6675 1275)(-6675 1425);
WIRE 16 -1 (-6600 1425)(-6675 1425);
WIRE 16 -1 (-7450 1525)(-6675 1525);
FORCEPROP 2 LAST SIG_NAME VR_PVSA_CPU1_BIREF1
J 0
(-7440 1540);
DISPLAY 0.617021 (-7440 1540);
PAINT ORANGE (-7440 1540);
WIRE 16 -1 (-6675 1425)(-6675 1525);
WIRE 16 -1 (-5175 1525)(-6675 1525);
WIRE 16 -1 (-5175 1925)(-5175 1525);
WIRE 16 -1 (-4275 1925)(-5175 1925);
WIRE 16 -1 (-5225 1975)(-4275 1975);
WIRE 16 -1 (-5225 1575)(-5225 1975);
WIRE 16 -1 (-7450 1575)(-6150 1575);
FORCEPROP 2 LAST SIG_NAME A_TSENSE_PVSA_CPU1
J 0
(-7440 1590);
DISPLAY 0.617021 (-7440 1590);
PAINT ORANGE (-7440 1590);
WIRE 16 -1 (-5225 1575)(-6150 1575);
WIRE 16 -1 (-6150 750)(-6150 1575);
WIRE 3 2175 (-6250 950)(-6250 1625);
WIRE 3 2175 (-6725 1625)(-6250 1625);
WIRE 3 2175 (-6725 950)(-6250 950);
WIRE 3 2175 (-6725 950)(-6725 1625);
WIRE 3 682 (-7250 1200)(-7250 1400);
WIRE 3 682 (-6800 1200)(-7250 1200);
WIRE 3 682 (-7250 1400)(-6800 1400);
WIRE 3 682 (-6800 1400)(-6800 1200);
WIRE 16 -1 (-3375 2375)(-1200 2375);
FORCEPROP 0 LAST VOLTAGE 3.6
J 0
(-1875 2450);
DISPLAY 1.021277 (-1875 2450);
PAINT SKYBLUE (-1875 2450);
DISPLAY INVISIBLE (-1875 2450);
FORCEPROP 2 LAST SIG_NAME VR_PVCCIN_CPU1_PWM4
J 0
(-1890 2390);
DISPLAY 0.617021 (-1890 2390);
PAINT ORANGE (-1890 2390);
WIRE 16 -1 (-3375 2475)(-1200 2475);
FORCEPROP 0 LAST VOLTAGE 3.6
J 0
(-1875 2550);
DISPLAY 1.021277 (-1875 2550);
PAINT SKYBLUE (-1875 2550);
DISPLAY INVISIBLE (-1875 2550);
FORCEPROP 2 LAST SIG_NAME VR_PVCCIN_CPU1_PWM2
J 0
(-1890 2490);
DISPLAY 0.617021 (-1890 2490);
PAINT ORANGE (-1890 2490);
WIRE 16 -1 (-3375 2525)(-1200 2525);
FORCEPROP 0 LAST VOLTAGE 3.6
J 0
(-1875 2600);
DISPLAY 1.021277 (-1875 2600);
PAINT SKYBLUE (-1875 2600);
DISPLAY INVISIBLE (-1875 2600);
FORCEPROP 2 LAST SIG_NAME VR_PVCCIN_CPU1_PWM1
J 0
(-1890 2540);
DISPLAY 0.617021 (-1890 2540);
PAINT ORANGE (-1890 2540);
WIRE 16 -1 (-3375 2575)(-1200 2575);
FORCEPROP 0 LAST VOLTAGE 3.6
J 0
(-1875 2650);
DISPLAY 1.021277 (-1875 2650);
PAINT SKYBLUE (-1875 2650);
DISPLAY INVISIBLE (-1875 2650);
FORCEPROP 2 LAST SIG_NAME VR_PVSA_CPU1_PWM
J 0
(-1890 2590);
DISPLAY 0.617021 (-1890 2590);
PAINT ORANGE (-1890 2590);
WIRE 16 -1 (-5350 2225)(-4275 2225);
WIRE 16 -1 (-5350 1725)(-5350 2225);
WIRE 16 -1 (-7450 1725)(-5350 1725);
FORCEPROP 0 LAST VOLTAGE 0.8
J 0
(-7425 1800);
DISPLAY 1.021277 (-7425 1800);
PAINT SKYBLUE (-7425 1800);
DISPLAY INVISIBLE (-7425 1800);
FORCEPROP 2 LAST SIG_NAME VR_PVCCIN_CPU1_AVINSEN
J 0
(-7440 1740);
DISPLAY 0.617021 (-7440 1740);
PAINT ORANGE (-7440 1740);
WIRE 16 -1 (-5300 2275)(-5400 2275);
WIRE 16 -1 (-5400 1825)(-5400 2275);
WIRE 16 -1 (-7450 1825)(-5400 1825);
FORCEPROP 2 LAST SIG_NAME FM_PVCCIN_PVCCSA_CPU1_EN_LVC1
J 0
(-7457 1844);
DISPLAY 0.617021 (-7457 1844);
PAINT ORANGE (-7457 1844);
WIRE 16 -1 (-5475 2325)(-4275 2325);
WIRE 16 -1 (-5475 1875)(-5475 2325);
WIRE 16 -1 (-5925 1375)(-5925 1875);
WIRE 16 -1 (-5475 1875)(-5925 1875);
WIRE 16 -1 (-7450 1875)(-5925 1875);
FORCEPROP 0 LAST VOLTAGE 3.6
J 0
(-7450 1950);
DISPLAY 1.021277 (-7450 1950);
PAINT SKYBLUE (-7450 1950);
DISPLAY INVISIBLE (-7450 1950);
FORCEPROP 2 LAST SIG_NAME A_TSENSE_PVCCIN_CPU1
J 0
(-7465 1890);
DISPLAY 0.617021 (-7465 1890);
PAINT ORANGE (-7465 1890);
WIRE 16 -1 (-5650 1925)(-7450 1925);
FORCEPROP 2 LAST SIG_NAME VSENSE_PVSA_CPU1_N
J 0
(-7465 1940);
DISPLAY 0.617021 (-7465 1940);
PAINT ORANGE (-7465 1940);
WIRE 16 -1 (-5650 1975)(-5650 1925);
WIRE 16 -1 (-5550 1925)(-5650 1925);
WIRE 16 -1 (-5550 2425)(-5550 1925);
WIRE 16 -1 (-4275 2425)(-5550 2425);
WIRE 16 -1 (-6550 2250)(-7450 2250);
FORCEPROP 2 LAST SIG_NAME VSENSE_PVCCIN_CPU1_N
J 0
(-7465 2265);
DISPLAY 0.617021 (-7465 2265);
PAINT ORANGE (-7465 2265);
WIRE 16 -1 (-6550 2275)(-6550 2250);
WIRE 16 -1 (-6150 2250)(-6550 2250);
WIRE 16 -1 (-6150 2525)(-6150 2250);
WIRE 16 -1 (-4275 2525)(-6150 2525);
WIRE 16 -1 (-6675 2575)(-6550 2575);
WIRE 16 -1 (-6550 2475)(-6550 2575);
WIRE 16 -1 (-4275 2575)(-6550 2575);
FORCEPROP 2 LAST SIG_NAME VSENSE_PVCCIN_CPU1_AVSP
J 0
(-5740 2590);
DISPLAY 0.617021 (-5740 2590);
PAINT ORANGE (-5740 2590);
FORCEPROP 2 LASTPROP $XRERR UNIQUE?
J 0
(-5980 2590);
DISPLAY 0.638298 (-5980 2590);
PAINT MONO (-5980 2590);
DISPLAY INVISIBLE (-5980 2590);
WIRE 16 -1 (-5000 3500)(-4900 3500);
WIRE 16 -1 (-5025 3350)(-4900 3350);
WIRE 16 -1 (-4900 3500)(-4900 3350);
WIRE 16 -1 (-4275 2725)(-4900 2725);
WIRE 16 -1 (-4900 2725)(-4900 3350);
WIRE 16 -1 (-7450 2725)(-4900 2725);
FORCEPROP 2 LAST SIG_NAME ISENSE_PVCCIN_CPU1_PH5_IMON
J 0
(-7440 2740);
DISPLAY 0.617021 (-7440 2740);
PAINT ORANGE (-7440 2740);
WIRE 16 -1 (-5450 3500)(-5350 3500);
WIRE 16 -1 (-5475 3350)(-5350 3350);
WIRE 16 -1 (-5350 3500)(-5350 3350);
WIRE 16 -1 (-5350 2775)(-5350 3350);
WIRE 16 -1 (-5350 2775)(-4275 2775);
WIRE 16 -1 (-7450 2775)(-5350 2775);
FORCEPROP 2 LAST SIG_NAME ISENSE_PVCCIN_CPU1_PH4_IMON
J 0
(-7440 2790);
DISPLAY 0.617021 (-7440 2790);
PAINT ORANGE (-7440 2790);
WIRE 16 -1 (-7450 2075)(-6450 2075);
FORCEPROP 2 LAST SIG_NAME VSENSE_PVSA_CPU1_P
J 0
(-7465 2090);
DISPLAY 0.617021 (-7465 2090);
PAINT ORANGE (-7465 2090);
WIRE 16 -1 (-6150 3500)(-6100 3500);
WIRE 16 -1 (-6150 3500)(-6150 3350);
WIRE 16 -1 (-6075 3350)(-6150 3350);
WIRE 16 -1 (-6150 3125)(-6150 3350);
WIRE 16 -1 (-4275 3125)(-6150 3125);
WIRE 16 -1 (-7450 3125)(-6150 3125);
FORCEPROP 2 LAST SIG_NAME VR_PVCCIN_CPU1_AIREF3
J 2
(-7025 3140);
DISPLAY 0.617021 (-7025 3140);
PAINT ORANGE (-7025 3140);
WIRE 16 -1 (-6275 3500)(-6200 3500);
WIRE 16 -1 (-6300 3350)(-6200 3350);
WIRE 16 -1 (-6200 3500)(-6200 3350);
WIRE 16 -1 (-6200 2875)(-6200 3350);
WIRE 16 -1 (-6200 2875)(-4275 2875);
WIRE 16 -1 (-7450 2875)(-6200 2875);
FORCEPROP 2 LAST SIG_NAME ISENSE_PVCCIN_CPU1_PH2_IMON
J 0
(-7440 2890);
DISPLAY 0.617021 (-7440 2890);
PAINT ORANGE (-7440 2890);
WIRE 16 -1 (-6950 3500)(-6875 3500);
WIRE 16 -1 (-6950 3500)(-6950 3350);
WIRE 16 -1 (-6850 3350)(-6950 3350);
WIRE 16 -1 (-6950 3225)(-6950 3350);
WIRE 16 -1 (-4275 3225)(-6950 3225);
WIRE 16 -1 (-7450 3225)(-6950 3225);
FORCEPROP 2 LAST SIG_NAME VR_PVCCIN_CPU1_AIREF1
J 2
(-7025 3240);
DISPLAY 0.617021 (-7025 3240);
PAINT ORANGE (-7025 3240);
WIRE 16 -1 (-5725 3500)(-5650 3500);
WIRE 16 -1 (-5725 3500)(-5725 3350);
WIRE 16 -1 (-5625 3350)(-5725 3350);
WIRE 16 -1 (-5725 3075)(-5725 3350);
WIRE 16 -1 (-4275 3075)(-5725 3075);
WIRE 16 -1 (-7450 3075)(-5725 3075);
FORCEPROP 2 LAST SIG_NAME VR_PVCCIN_CPU1_AIREF4
J 2
(-7025 3090);
DISPLAY 0.617021 (-7025 3090);
PAINT ORANGE (-7025 3090);
WIRE 16 -1 (-5275 3500)(-5200 3500);
WIRE 16 -1 (-5275 3500)(-5275 3350);
WIRE 16 -1 (-5175 3350)(-5275 3350);
WIRE 16 -1 (-5275 3025)(-5275 3350);
WIRE 16 -1 (-4275 3025)(-5275 3025);
WIRE 16 -1 (-7450 3025)(-5275 3025);
FORCEPROP 2 LAST SIG_NAME VR_PVCCIN_CPU1_AIREF5
J 2
(-7025 3040);
DISPLAY 0.617021 (-7025 3040);
PAINT ORANGE (-7025 3040);
WIRE 3 2175 (-6975 3700)(-4875 3700);
WIRE 3 2175 (-4875 3700)(-4875 2975);
WIRE 3 2175 (-6975 3700)(-6975 2975);
WIRE 3 2175 (-6975 2975)(-4875 2975);
WIRE 16 -1 (-6675 3500)(-6600 3500);
WIRE 16 -1 (-6700 3350)(-6600 3350);
WIRE 16 -1 (-6600 3500)(-6600 3350);
WIRE 16 -1 (-6600 2925)(-6600 3350);
WIRE 16 -1 (-6600 2925)(-4275 2925);
WIRE 16 -1 (-7450 2925)(-6600 2925);
FORCEPROP 2 LAST SIG_NAME ISENSE_PVCCIN_CPU1_PH1_IMON
J 0
(-7440 2940);
DISPLAY 0.617021 (-7440 2940);
PAINT ORANGE (-7440 2940);
WIRE 16 -1 (-6250 2075)(-6075 2075);
WIRE 16 -1 (-5650 2475)(-4275 2475);
WIRE 16 -1 (-5650 2175)(-5650 2275);
WIRE 16 -1 (-5650 2275)(-5650 2475);
FORCEPROP 2 LAST SIG_NAME VSENSE_PVSA_CPU1_BVSP
J 0
(-5690 2490);
DISPLAY 0.617021 (-5690 2490);
PAINT ORANGE (-5690 2490);
FORCEPROP 2 LASTPROP $XRERR UNIQUE?
J 0
(-5930 2490);
DISPLAY 0.638298 (-5930 2490);
PAINT MONO (-5930 2490);
DISPLAY INVISIBLE (-5930 2490);
WIRE 16 -1 (-6075 2075)(-6075 2275);
WIRE 16 -1 (-6075 2275)(-5650 2275);
WIRE 16 -1 (-5100 2275)(-4650 2275);
FORCEPROP 2 LAST SIG_NAME VR_PVCCIN_CPU1_VREN
J 0
(-5100 2290);
DISPLAY 0.617021 (-5100 2290);
PAINT ORANGE (-5100 2290);
FORCEPROP 2 LASTPROP $XRERR UNIQUE?
J 0
(-5340 2290);
DISPLAY 0.638298 (-5340 2290);
PAINT MONO (-5340 2290);
DISPLAY INVISIBLE (-5340 2290);
WIRE 16 -1 (-4650 2275)(-4275 2275);
FORCEPROP 0 LAST VOLTAGE 3.3
J 0
(-4450 2325);
DISPLAY 1.021277 (-4450 2325);
PAINT SKYBLUE (-4450 2325);
DISPLAY INVISIBLE (-4450 2325);
WIRE 16 -1 (-4650 2275)(-4650 4300);
WIRE 16 -1 (-4825 1825)(-4275 1825);
FORCEPROP 0 LAST VOLTAGE 3.3
J 0
(-4550 1875);
DISPLAY 1.021277 (-4550 1875);
PAINT SKYBLUE (-4550 1875);
DISPLAY INVISIBLE (-4550 1875);
WIRE 16 -1 (-4825 1025)(-4825 1825);
FORCEPROP 0 LAST SIG_NAME VR_PVCCIN_CPU1_XADDR1
R 1
J 0
(-4835 1085);
DISPLAY 0.617021 (-4835 1085);
PAINT ORANGE (-4835 1085);
FORCEPROP 2 LASTPROP $XRERR UNIQUE?
J 0
(-5075 1085);
DISPLAY 0.638298 (-5075 1085);
PAINT MONO (-5075 1085);
DISPLAY INVISIBLE (-5075 1085);
WIRE 16 -1 (-5900 3500)(-5800 3500);
WIRE 16 -1 (-5925 3350)(-5800 3350);
WIRE 16 -1 (-5800 3500)(-5800 3350);
WIRE 16 -1 (-5800 2825)(-5800 3350);
WIRE 16 -1 (-5800 2825)(-4275 2825);
WIRE 16 -1 (-7450 2825)(-5800 2825);
FORCEPROP 2 LAST SIG_NAME ISENSE_PVCCIN_CPU1_PH3_IMON
J 0
(-7440 2840);
DISPLAY 0.617021 (-7440 2840);
PAINT ORANGE (-7440 2840);
WIRE 3 682 (-6975 3850)(-4875 3850);
WIRE 3 682 (-4875 3750)(-4875 3850);
WIRE 3 682 (-6975 3850)(-6975 3750);
WIRE 3 682 (-6975 3750)(-4875 3750);
WIRE 16 -1 (-5475 3900)(-5650 3900);
WIRE 16 -1 (-5650 4350)(-5650 3900);
WIRE 16 -1 (-7450 3900)(-5650 3900);
FORCEPROP 2 LAST SIG_NAME SVID_CLK0_CPU1_R
J 0
(-7437 3920);
DISPLAY 0.617021 (-7437 3920);
PAINT ORANGE (-7437 3920);
WIRE 16 -1 (-6550 3500)(-6475 3500);
WIRE 16 -1 (-6550 3500)(-6550 3350);
WIRE 16 -1 (-6450 3350)(-6550 3350);
WIRE 16 -1 (-6550 3175)(-6550 3350);
WIRE 16 -1 (-4275 3175)(-6550 3175);
WIRE 16 -1 (-7450 3175)(-6550 3175);
FORCEPROP 2 LAST SIG_NAME VR_PVCCIN_CPU1_AIREF2
J 2
(-7025 3190);
DISPLAY 0.617021 (-7025 3190);
PAINT ORANGE (-7025 3190);
WIRE 16 -1 (-7450 2575)(-6875 2575);
FORCEPROP 2 LAST SIG_NAME VSENSE_PVCCIN_CPU1_P
J 0
(-7465 2590);
DISPLAY 0.617021 (-7465 2590);
PAINT ORANGE (-7465 2590);
WIRE 16 -1 (-2525 2175)(-3375 2175);
WIRE 16 -1 (-2525 1775)(-2525 2175);
WIRE 16 -1 (-900 1775)(-2525 1775);
FORCEPROP 2 LAST SIG_NAME SMB_VR_STBY_LVC3_SDA
J 0
(-1565 1790);
DISPLAY 0.617021 (-1565 1790);
PAINT ORANGE (-1565 1790);
WIRE 16 -1 (-3375 3025)(-3150 3025);
WIRE 16 -1 (-2475 3025)(-3150 3025);
WIRE 16 -1 (-3150 3900)(-3150 3025);
FORCEPROP 0 LAST SIG_NAME IRQ_PVCCIN_CPU1_VRHOT_LVC3_R_N
J 0
(-3275 3035);
DISPLAY 0.617021 (-3275 3035);
PAINT ORANGE (-3275 3035);
FORCEPROP 2 LASTPROP $XRERR UNIQUE?
J 0
(-3515 3035);
DISPLAY 0.638298 (-3515 3035);
PAINT MONO (-3515 3035);
DISPLAY INVISIBLE (-3515 3035);
WIRE 16 -1 (-4500 3325)(-4275 3325);
WIRE 16 -1 (-4500 3900)(-4500 3325);
WIRE 16 -1 (-5275 3900)(-4500 3900);
FORCEPROP 2 LAST SIG_NAME SVID_VCLK_PVCCIN_CPU1
J 0
(-5115 3915);
DISPLAY 0.617021 (-5115 3915);
PAINT ORANGE (-5115 3915);
FORCEPROP 2 LASTPROP $XRERR UNIQUE?
J 0
(-5355 3915);
DISPLAY 0.638298 (-5355 3915);
PAINT MONO (-5355 3915);
DISPLAY INVISIBLE (-5355 3915);
WIRE 16 -1 (-4275 3425)(-4350 3425);
WIRE 16 -1 (-4350 4075)(-4350 3425);
FORCEPROP 0 LAST VOLTAGE 3.3
J 0
(-4350 3800);
DISPLAY 1.021277 (-4350 3800);
PAINT SKYBLUE (-4350 3800);
DISPLAY INVISIBLE (-4350 3800);
WIRE 16 -1 (-4350 4175)(-4350 4075);
WIRE 16 -1 (-4050 4075)(-4350 4075);
WIRE 16 -1 (-4050 4025)(-4050 4075);
WIRE 16 -1 (-3650 4075)(-4050 4075);
FORCEPROP 2 LAST SIG_NAME VR_PVCCIN_CPU1_VDD
J 0
(-4115 4090);
DISPLAY 0.617021 (-4115 4090);
PAINT ORANGE (-4115 4090);
FORCEPROP 2 LASTPROP $XRERR UNIQUE?
J 0
(-4355 4090);
DISPLAY 0.638298 (-4355 4090);
PAINT MONO (-4355 4090);
DISPLAY INVISIBLE (-4355 4090);
WIRE 16 -1 (-3650 4025)(-3650 4075);
WIRE 16 -1 (-6750 4425)(-7450 4425);
FORCEPROP 2 LAST SIG_NAME VR_PVCCIN_CPU1_AVINSEN
J 0
(-7465 4440);
DISPLAY 0.617021 (-7465 4440);
PAINT ORANGE (-7465 4440);
WIRE 16 -1 (-6750 4300)(-6750 4425);
WIRE 16 -1 (-6150 4425)(-6750 4425);
WIRE 16 -1 (-6150 4325)(-6150 4425);
WIRE 16 -1 (-6150 4425)(-6150 4475);
WIRE 3 682 (-6850 4475)(-6850 3950);
WIRE 3 682 (-6450 4475)(-6850 4475);
WIRE 3 682 (-6850 3950)(-6450 3950);
WIRE 3 682 (-6450 3950)(-6450 4475);
WIRE 16 -1 (-2225 3650)(-2225 3175);
WIRE 16 -1 (-3375 3175)(-2225 3175);
FORCEPROP 2 LAST SIG_NAME PU_VR_PVCCIN_CPU1_IMON
J 0
(-3275 3190);
DISPLAY 0.617021 (-3275 3190);
PAINT ORANGE (-3275 3190);
FORCEPROP 2 LASTPROP $XRERR UNIQUE?
J 0
(-3515 3190);
DISPLAY 0.638298 (-3515 3190);
PAINT MONO (-3515 3190);
DISPLAY INVISIBLE (-3515 3190);
WIRE 16 -1 (-1225 2775)(-1375 2775);
WIRE 16 -1 (-1375 2775)(-1375 3650);
WIRE 16 -1 (-2400 2775)(-1375 2775);
FORCEPROP 0 LAST SIG_NAME SVID_DIO0_CPU1_R
J 0
(-1900 2785);
DISPLAY 0.617021 (-1900 2785);
PAINT ORANGE (-1900 2785);
WIRE 16 -1 (-4500 1775)(-4275 1775);
FORCEPROP 0 LAST VOLTAGE 3.3
J 0
(-4375 1825);
DISPLAY 1.021277 (-4375 1825);
PAINT SKYBLUE (-4375 1825);
DISPLAY INVISIBLE (-4375 1825);
WIRE 16 -1 (-4500 1025)(-4500 1775);
FORCEPROP 0 LAST SIG_NAME VR_PVCCIN_CPU1_XADDR2
R 1
J 0
(-4510 1085);
DISPLAY 0.617021 (-4510 1085);
PAINT ORANGE (-4510 1085);
FORCEPROP 2 LASTPROP $XRERR UNIQUE?
J 0
(-4750 1085);
DISPLAY 0.638298 (-4750 1085);
PAINT MONO (-4750 1085);
DISPLAY INVISIBLE (-4750 1085);
WIRE 3 682 (-4400 2075)(-4350 2075);
WIRE 3 682 (-4400 2175)(-4400 2075);
WIRE 3 682 (-4350 2175)(-4400 2175);
WIRE 16 -1 (-2600 2075)(-3375 2075);
WIRE 16 -1 (-2600 2075)(-2600 1525);
WIRE 16 -1 (-900 1525)(-2600 1525);
FORCEPROP 2 LAST SIG_NAME SMB_VR_STBY_LVC3_SCL
J 0
(-1565 1540);
DISPLAY 0.617021 (-1565 1540);
PAINT ORANGE (-1565 1540);
WIRE 16 -1 (-2875 2725)(-2275 2725);
WIRE 16 -1 (-2875 2725)(-2875 3825);
WIRE 16 -1 (-3375 2725)(-2875 2725);
FORCEPROP 2 LAST SIG_NAME PWRGD_PVSA_CPU1_R
J 0
(-3275 2740);
DISPLAY 0.617021 (-3275 2740);
PAINT ORANGE (-3275 2740);
FORCEPROP 2 LASTPROP $XRERR UNIQUE?
J 0
(-3515 2740);
DISPLAY 0.638298 (-3515 2740);
PAINT MONO (-3515 2740);
DISPLAY INVISIBLE (-3515 2740);
WIRE 16 -1 (-2225 2925)(-3375 2925);
FORCEPROP 2 LAST SIG_NAME SVID_VALERT_VCCIN_CPU1
J 0
(-3275 2940);
DISPLAY 0.617021 (-3275 2940);
PAINT ORANGE (-3275 2940);
FORCEPROP 2 LASTPROP $XRERR UNIQUE?
J 0
(-3515 2940);
DISPLAY 0.638298 (-3515 2940);
PAINT MONO (-3515 2940);
DISPLAY INVISIBLE (-3515 2940);
WIRE 16 -1 (-3375 2825)(-1200 2825);
FORCEPROP 2 LAST SIG_NAME VR_PVCCIN_CPU1_VD12
J 0
(-1900 2840);
DISPLAY 0.617021 (-1900 2840);
PAINT ORANGE (-1900 2840);
WIRE 16 -1 (-2600 2775)(-3375 2775);
FORCEPROP 0 LAST SIG_NAME SVID_VDIO_PVCCIN_CPU1
J 0
(-3275 2785);
DISPLAY 0.617021 (-3275 2785);
PAINT ORANGE (-3275 2785);
FORCEPROP 2 LASTPROP $XRERR UNIQUE?
J 0
(-3515 2785);
DISPLAY 0.638298 (-3515 2785);
PAINT MONO (-3515 2785);
DISPLAY INVISIBLE (-3515 2785);
WIRE 16 -1 (-1200 3025)(-2275 3025);
FORCEPROP 0 LAST SIG_NAME IRQ_PVCCIN_CPU1_VRHOT_LVC3_N
J 0
(-1925 3035);
DISPLAY 0.617021 (-1925 3035);
PAINT ORANGE (-1925 3035);
WIRE 16 -1 (-3375 2325)(-1200 2325);
FORCEPROP 2 LAST SIG_NAME VR_PVCCIN_CPU1_PWM5
J 0
(-1890 2340);
DISPLAY 0.617021 (-1890 2340);
PAINT ORANGE (-1890 2340);
WIRE 16 -1 (-2375 4025)(-2375 3325);
WIRE 16 -1 (-3375 3325)(-2375 3325);
FORCEPROP 2 LAST SIG_NAME PU_VR_PVCCIN_CPU1_FLT1_SMBALT_N_IMON
J 0
(-3298 3341);
DISPLAY 0.617021 (-3298 3341);
PAINT ORANGE (-3298 3341);
FORCEPROP 2 LASTPROP $XRERR UNIQUE?
J 0
(-3538 3341);
DISPLAY 0.638298 (-3538 3341);
PAINT MONO (-3538 3341);
DISPLAY INVISIBLE (-3538 3341);
WIRE 16 -1 (-1450 2250)(-1450 3375);
WIRE 16 -1 (-1450 3375)(-1300 3375);
WIRE 16 -1 (-2725 3825)(-2725 3375);
WIRE 16 -1 (-2725 3375)(-1450 3375);
WIRE 16 -1 (-3375 3375)(-2725 3375);
FORCEPROP 2 LAST SIG_NAME VR_VRRDY_PVCCIN_CPU1
J 0
(-3275 3390);
DISPLAY 0.617021 (-3275 3390);
PAINT ORANGE (-3275 3390);
FORCEPROP 2 LASTPROP $XRERR UNIQUE?
J 0
(-3515 3390);
DISPLAY 0.638298 (-3515 3390);
PAINT MONO (-3515 3390);
DISPLAY INVISIBLE (-3515 3390);
WIRE 3 682 (-2300 1850)(-2300 1450);
WIRE 3 682 (-1875 1850)(-2300 1850);
WIRE 3 682 (-2300 1450)(-1875 1450);
WIRE 3 682 (-1875 1450)(-1875 1850);
WIRE 16 -1 (-2025 2925)(-1200 2925);
FORCEPROP 2 LAST SIG_NAME SVID_ALERT0_CPU1_R_N
J 0
(-1900 2935);
DISPLAY 0.617021 (-1900 2935);
PAINT ORANGE (-1900 2935);
WIRE 16 -1 (-2075 2725)(-1200 2725);
FORCEPROP 2 LAST SIG_NAME PWRGD_PVSA_CPU1
J 0
(-1900 2740);
DISPLAY 0.617021 (-1900 2740);
PAINT ORANGE (-1900 2740);
WIRE 3 682 (-2100 3950)(-1750 3950);
WIRE 3 682 (-2100 4350)(-2100 3950);
WIRE 3 682 (-1750 3950)(-1750 4350);
WIRE 3 682 (-1750 4350)(-2100 4350);
WIRE 16 -1 (-1975 1100)(-1975 1175);
WIRE 16 -1 (-1575 1175)(-1975 1175);
FORCEPROP 2 LAST SIG_NAME VR_PVCCIN_CPU1_VD12
J 0
(-1890 1190);
DISPLAY 0.617021 (-1890 1190);
PAINT ORANGE (-1890 1190);
WIRE 16 -1 (-1575 1175)(-1000 1175);
WIRE 16 -1 (-1575 1100)(-1575 1175);
WIRE 16 -1 (-1100 3375)(-600 3375);
FORCEPROP 2 LAST SIG_NAME PWRGD_PVCCIN_CPU1
J 0
(-1090 3390);
DISPLAY 0.617021 (-1090 3390);
PAINT ORANGE (-1090 3390);
DOT 1 (-6300 1475);
DOT 1 (-6550 2575);
DOT 1 (-6550 2250);
DOT 1 (-6200 3350);
DOT 1 (-6675 1425);
DOT 1 (-4650 2275);
DOT 1 (-6600 2925);
DOT 1 (-6550 3350);
DOT 1 (-5725 3350);
DOT 1 (-5800 3350);
DOT 1 (-6150 3350);
DOT 1 (-6950 3350);
DOT 1 (-6600 3350);
DOT 1 (-5350 3350);
DOT 1 (-5275 3350);
DOT 1 (-4900 3350);
DOT 1 (-6200 2875);
DOT 1 (-6150 3125);
DOT 1 (-5275 3025);
DOT 1 (-6300 1425);
DOT 1 (-6150 1575);
DOT 1 (-6550 3175);
DOT 1 (-5650 2275);
DOT 1 (-5350 2775);
DOT 1 (-5800 2825);
DOT 1 (-2225 4375);
DOT 1 (-2375 4375);
DOT 1 (-2725 4375);
DOT 1 (-2875 4375);
DOT 1 (-3075 4375);
DOT 1 (-1450 3375);
DOT 1 (-1575 1175);
DOT 1 (-2875 2725);
DOT 1 (-4050 4075);
DOT 1 (-6150 4425);
DOT 1 (-4350 4075);
DOT 1 (-5650 1925);
DOT 1 (-5925 1875);
DOT 1 (-5650 3900);
DOT 1 (-5725 3075);
DOT 1 (-6675 1525);
DOT 1 (-1375 2775);
DOT 1 (-2050 3275);
DOT 1 (-3150 3025);
DOT 1 (-4900 2725);
DOT 1 (-6950 3225);
DOT 1 (-2725 3375);
DOT 1 (-5225 4700);
DOT 1 (-6750 4425);
FORCENOTE
CF7&CF8&CF9&CF10&CF11&CF12
(-8025 3700) 0;
DISPLAY LEFT (-8025 3700);
DISPLAY 0.872340 (-8025 3700);
PAINT RED (-8025 3700);
FORCENOTE
INFINEON:NOPOP
(-8025 3625) 0;
DISPLAY LEFT (-8025 3625);
DISPLAY 0.872340 (-8025 3625);
PAINT RED (-8025 3625);
FORCENOTE
FAIRCHILD:POP
(-8025 3550) 0;
DISPLAY LEFT (-8025 3550);
DISPLAY 0.872340 (-8025 3550);
PAINT RED (-8025 3550);
FORCENOTE
RF7&RF8&RF9&RF10&RF11&RF12
(-8025 3775) 0;
DISPLAY LEFT (-8025 3775);
DISPLAY 0.872340 (-8025 3775);
PAINT RED (-8025 3775);
FORCENOTE
TP FAB1 DELETE RES 0203
(-7800 1125) 0;
DISPLAY LEFT (-7800 1125);
DISPLAY 1.021277 (-7800 1125);
PAINT RED (-7800 1125);
FORCENOTE
ROOM=PROC_VRD_VCCIN_CPU1
(-8005 183) 0;
DISPLAY LEFT (-8005 183);
DISPLAY 2.510638 (-8005 183);
PAINT PURPLE (-8005 183);
FORCENOTE
TP FAB4 CHANGE RF12 TO 1.1KOHM FOR VR FAILCHILD, SINGLE SIDE BOM 20170123
(-6725 875) 0;
DISPLAY LEFT (-6725 875);
DISPLAY 0.638298 (-6725 875);
PAINT RED (-6725 875);
FORCENOTE
TP FAB1 CO-LAY WITH FAIRCHILD PARTS 1203
(-6712 906) 0;
DISPLAY LEFT (-6712 906);
DISPLAY 0.680851 (-6712 906);
PAINT RED (-6712 906);
FORCENOTE
TP FAB1 NC 0321
(-4900 2650) 0;
DISPLAY LEFT (-4900 2650);
DISPLAY 1.021277 (-4900 2650);
PAINT RED (-4900 2650);
FORCENOTE
TP FAB1 NC 0321
(-4975 2150) 0;
DISPLAY LEFT (-4975 2150);
DISPLAY 1.021277 (-4975 2150);
PAINT RED (-4975 2150);
FORCENOTE
TP FAB4 CHANGE RF7-11 TO 953OHM FOR VR FAILCHILD, SINGLE SIDE BOM 20170123
(-6550 2875) 0;
DISPLAY LEFT (-6550 2875);
DISPLAY 0.638298 (-6550 2875);
PAINT RED (-6550 2875);
FORCENOTE
TP FAB1 CO-LAY WITH FAIRCHILD PARTS 1203
(-6562 2931) 0;
DISPLAY LEFT (-6562 2931);
DISPLAY 0.638298 (-6562 2931);
PAINT RED (-6562 2931);
FORCENOTE
TP FAB1 DELETE RES 0203
(-6950 3775) 0;
DISPLAY LEFT (-6950 3775);
DISPLAY 1.021277 (-6950 3775);
PAINT RED (-6950 3775);
FORCENOTE
TP FAB1 NC 0321
(-4850 2950) 0;
DISPLAY LEFT (-4850 2950);
DISPLAY 1.021277 (-4850 2950);
PAINT RED (-4850 2950);
FORCENOTE
TP FAB1 CHANGE TO 1K OHM 0218
(-2225 4400) 0;
DISPLAY LEFT (-2225 4400);
DISPLAY 1.021277 (-2225 4400);
PAINT RED (-2225 4400);
FORCENOTE
TP FAB1 NC 0321
(-3300 3100) 0;
DISPLAY LEFT (-3300 3100);
DISPLAY 1.021277 (-3300 3100);
PAINT RED (-3300 3100);
FORCENOTE
TP FAB1 NC 0321
(-3325 2650) 0;
DISPLAY LEFT (-3325 2650);
DISPLAY 1.021277 (-3325 2650);
PAINT RED (-3325 2650);
FORCENOTE
TP FAB1 DEL RES 0314
(-2475 1900) 0;
DISPLAY LEFT (-2475 1900);
DISPLAY 1.021277 (-2475 1900);
PAINT RED (-2475 1900);
FORCENOTE
TP FAB1 NC 0321
(-3325 2250) 0;
DISPLAY LEFT (-3325 2250);
DISPLAY 1.021277 (-3325 2250);
PAINT RED (-3325 2250);
FORCENOTE
TP FAB3 CHANGE CAP 0912
(-6850 4500) 0;
DISPLAY LEFT (-6850 4500);
DISPLAY 0.638298 (-6850 4500);
PAINT RED (-6850 4500);
QUIT
